-- pcdb file, Rev:1.0 written by Allegro Design Entry HDL 17.2-2016 S081 (4005846) 1/11/2022 on Wed Feb 22 14:39:29 2023
#ISCELL
  pure_quanta quanta_title_block_c *
  *
#ISCELL
  pure_quanta quanta_title_block_c *
  *
#ISCELL
  pure_quanta quanta_title_block_c *
  *
#ISCELL
  pure_quanta quanta_title_block_c *
  *
#ISCELL
  pure_quanta quanta_title_block_c *
  *
#ISCELL
  pure_quanta quanta_title_block_c *
  *
#ISCELL
  pure_quanta quanta_title_block_c *
  *
#ISCELL
  pure_quanta quanta_title_block_c *
  *
#ISCELL
  pure_quanta quanta_title_block_c *
  *
#ISCELL
  logical_power design_note *
  *
#ISCELL
  mstr_misc dns *
  *
#ISCELL
  pure_quanta quanta_title_block_c *
  *
#ISCELL
  logical_power universal_power *
  page10_i173
#ISCELL
  logical_power universal_gnd *
  page10_i174
#ISCELL
  logical_power universal_gnd *
  page10_i175
#ISCELL
  standard offpage *
  page10_i188
#ISCELL
  standard offpage *
  page10_i189
#ISCELL
  standard offpage *
  page10_i190
#ISCELL
  standard offpage *
  page10_i225
#ISCELL
  standard offpage *
  page10_i226
#ISCELL
  standard offpage *
  page10_i232
#ISCELL
  standard offpage *
  page10_i233
#ISCELL
  standard offpage *
  page10_i234
#ISCELL
  standard offpage *
  page10_i235
#ISCELL
  standard offpage *
  page10_i236
#ISCELL
  standard offpage *
  page10_i237
#ISCELL
  standard offpage *
  page10_i248
#ISCELL
  standard offpage *
  page10_i249
#ISCELL
  standard offpage *
  page10_i250
#ISCELL
  standard offpage *
  page10_i251
#ISCELL
  standard offpage *
  page10_i252
#ISCELL
  standard offpage *
  page10_i253
#ISCELL
  standard offpage *
  page10_i254
#ISCELL
  standard offpage *
  page10_i255
#ISCELL
  standard offpage *
  page10_i256
#ISCELL
  standard offpage *
  page10_i257
#ISCELL
  standard offpage *
  page10_i258
#ISCELL
  standard offpage *
  page10_i259
#ISCELL
  standard offpage *
  page10_i260
#ISCELL
  standard offpage *
  page10_i261
#ISCELL
  standard offpage *
  page10_i262
#ISCELL
  standard offpage *
  page10_i263
#ISCELL
  standard offpage *
  page10_i264
#ISCELL
  standard offpage *
  page10_i265
#ISCELL
  standard offpage *
  page10_i266
#ISCELL
  standard offpage *
  page10_i267
#ISCELL
  standard offpage *
  page10_i272
#ISCELL
  standard offpage *
  page10_i273
#ISCELL
  standard offpage *
  page10_i274
#ISCELL
  standard offpage *
  page10_i275
#ISCELL
  standard offpage *
  page10_i276
#ISCELL
  standard offpage *
  page10_i277
#ISCELL
  standard offpage *
  page10_i279
#ISCELL
  standard offpage *
  page10_i281
#ISCELL
  standard offpage *
  page10_i282
#ISCELL
  standard offpage *
  page10_i283
#ISCELL
  standard offpage *
  page10_i284
#ISCELL
  standard offpage *
  page10_i286
#ISCELL
  standard offpage *
  page10_i287
#ISCELL
  standard offpage *
  page10_i288
#ISCELL
  standard offpage *
  page10_i289
#ISCELL
  standard offpage *
  page10_i290
#ISCELL
  standard offpage *
  page10_i292
#CELL
  pure_quanta q_res *
  page10_i293
#ISCELL
  standard offpage *
  page10_i294
#ISCELL
  standard offpage *
  page10_i295
#ISCELL
  standard offpage *
  page10_i296
#ISCELL
  standard offpage *
  page10_i297
#ISCELL
  standard offpage *
  page10_i301
#ISCELL
  standard offpage *
  page10_i408
#ISCELL
  standard offpage *
  page10_i416
#ISCELL
  standard offpage *
  page10_i424
#ISCELL
  standard offpage *
  page10_i425
#ISCELL
  standard offpage *
  page10_i426
#ISCELL
  standard offpage *
  page10_i427
#ISCELL
  standard offpage *
  page10_i430
#ISCELL
  standard offpage *
  page10_i432
#ISCELL
  standard offpage *
  page10_i433
#ISCELL
  standard offpage *
  page10_i434
#ISCELL
  standard offpage *
  page10_i435
#ISCELL
  standard offpage *
  page10_i443
#ISCELL
  logical_power universal_power *
  page10_i446
#ISCELL
  logical_power universal_gnd *
  page10_i447
#CELL
  pure_quanta q_res *
  page10_i456
#ISCELL
  standard offpage *
  page10_i457
#CELL
  pure_quanta q_res *
  page10_i458
#CELL
  pure_quanta q_res *
  page10_i459
#ISCELL
  standard offpage *
  page10_i469
#ISCELL
  standard offpage *
  page10_i470
#ISCELL
  standard offpage *
  page10_i471
#ISCELL
  standard offpage *
  page10_i472
#ISCELL
  standard offpage *
  page10_i473
#ISCELL
  standard offpage *
  page10_i474
#ISCELL
  standard offpage *
  page10_i475
#ISCELL
  standard offpage *
  page10_i477
#ISCELL
  standard offpage *
  page10_i478
#ISCELL
  standard offpage *
  page10_i481
#ISCELL
  standard offpage *
  page10_i482
#ISCELL
  standard offpage *
  page10_i483
#ISCELL
  standard offpage *
  page10_i484
#ISCELL
  standard offpage *
  page10_i485
#ISCELL
  standard offpage *
  page10_i486
#ISCELL
  standard offpage *
  page10_i487
#ISCELL
  standard offpage *
  page10_i488
#ISCELL
  standard offpage *
  page10_i489
#ISCELL
  standard offpage *
  page10_i490
#ISCELL
  standard offpage *
  page10_i491
#ISCELL
  standard offpage *
  page10_i492
#ISCELL
  standard offpage *
  page10_i493
#ISCELL
  standard offpage *
  page10_i494
#ISCELL
  standard offpage *
  page10_i495
#ISCELL
  standard offpage *
  page10_i496
#ISCELL
  standard offpage *
  page10_i497
#ISCELL
  standard offpage *
  page10_i498
#ISCELL
  standard offpage *
  page10_i499
#ISCELL
  standard offpage *
  page10_i500
#CELL
  pure_quanta q_cap *
  page10_i503
#ISCELL
  logical_power universal_gnd *
  page10_i504
#ISCELL
  standard offpage *
  page10_i508
#ISCELL
  standard offpage *
  page10_i509
#ISCELL
  standard offpage *
  page10_i515
#ISCELL
  standard offpage *
  page10_i516
#ISCELL
  standard offpage *
  page10_i517
#ISCELL
  standard offpage *
  page10_i518
#ISCELL
  standard offpage *
  page10_i522
#ISCELL
  standard offpage *
  page10_i523
#ISCELL
  standard offpage *
  page10_i531
#ISCELL
  standard offpage *
  page10_i532
#ISCELL
  standard offpage *
  page10_i533
#ISCELL
  standard offpage *
  page10_i534
#ISCELL
  standard offpage *
  page10_i535
#ISCELL
  standard offpage *
  page10_i536
#ISCELL
  standard offpage *
  page10_i537
#ISCELL
  standard offpage *
  page10_i538
#ISCELL
  standard offpage *
  page10_i541
#ISCELL
  standard offpage *
  page10_i542
#ISCELL
  standard offpage *
  page10_i543
#ISCELL
  standard offpage *
  page10_i544
#CELL
  pure_quanta fconn168_me1016810202011_scm *
  page10_i553
#ISCELL
  standard offpage *
  page10_i554
#ISCELL
  standard offpage *
  page10_i555
#CELL
  pure_quanta q_res *
  page10_i557
#ISCELL
  standard offpage *
  page10_i558
#ISCELL
  standard offpage *
  page10_i560
#CELL
  pure_quanta q_res *
  page10_i562
#ISCELL
  standard offpage *
  page10_i563
#ISCELL
  standard offpage *
  page10_i564
#CELL
  pure_quanta q_res *
  page10_i565
#ISCELL
  standard offpage *
  page10_i566
#ISCELL
  standard offpage *
  page10_i567
#CELL
  pure_quanta q_res *
  page10_i568
#CELL
  pure_quanta q_res *
  page10_i569
#ISCELL
  standard offpage *
  page10_i570
#ISCELL
  standard offpage *
  page10_i571
#ISCELL
  standard offpage *
  page10_i572
#CELL
  pure_quanta q_cap *
  page10_i573
#CELL
  pure_quanta q_cap *
  page10_i574
#ISCELL
  standard offpage *
  page10_i575
#ISCELL
  standard offpage *
  page10_i576
#ISCELL
  standard offpage *
  page10_i577
#ISCELL
  standard offpage *
  page10_i578
#ISCELL
  standard offpage *
  page10_i579
#ISCELL
  mstr_misc dns *
  *
#ISCELL
  pure_quanta quanta_title_block_c *
  *
#ISCELL
  logical_power vccaux15 *
  page11_i101
#CELL
  pure_quanta q_res *
  page11_i110
#ISCELL
  standard offpage *
  page11_i115
#ISCELL
  standard offpage *
  page11_i116
#CELL
  pure_quanta q_res *
  page11_i117
#CELL
  pure_quanta q_res *
  page11_i118
#ISCELL
  standard offpage *
  page11_i124
#ISCELL
  standard offpage *
  page11_i125
#ISCELL
  standard offpage *
  page11_i126
#CELL
  pure_quanta q_res *
  page11_i128
#CELL
  pure_quanta q_res *
  page11_i129
#CELL
  pure_quanta q_res *
  page11_i130
#ISCELL
  standard offpage *
  page11_i136
#CELL
  pure_quanta q_res *
  page11_i171
#CELL
  pure_quanta q_res *
  page11_i175
#CELL
  pure_quanta q_res *
  page11_i176
#CELL
  pure_quanta q_res *
  page11_i179
#CELL
  pure_quanta q_res *
  page11_i181
#ISCELL
  standard offpage *
  page11_i193
#CELL
  pure_quanta q_res *
  page11_i194
#ISCELL
  logical_power universal_gnd *
  page11_i2
#CELL
  pure_quanta q_res *
  page11_i212
#ISCELL
  standard offpage *
  page11_i213
#CELL
  pure_quanta q_res *
  page11_i214
#ISCELL
  standard offpage *
  page11_i215
#ISCELL
  standard offpage *
  page11_i216
#ISCELL
  standard offpage *
  page11_i217
#CELL
  pure_quanta q_res *
  page11_i218
#CELL
  pure_quanta q_res *
  page11_i219
#ISCELL
  standard offpage *
  page11_i222
#CELL
  pure_quanta q_res *
  page11_i225
#ISCELL
  standard offpage *
  page11_i226
#CELL
  pure_quanta q_res *
  page11_i227
#ISCELL
  standard offpage *
  page11_i228
#ISCELL
  standard offpage *
  page11_i229
#CELL
  pure_quanta q_res *
  page11_i230
#CELL
  pure_quanta q_res *
  page11_i231
#CELL
  pure_quanta q_res *
  page11_i232
#CELL
  pure_quanta q_res *
  page11_i233
#CELL
  pure_quanta q_res *
  page11_i234
#ISCELL
  standard offpage *
  page11_i235
#ISCELL
  standard offpage *
  page11_i237
#CELL
  pure_quanta q_res *
  page11_i241
#ISCELL
  standard offpage *
  page11_i244
#CELL
  pure_quanta q_res *
  page11_i245
#ISCELL
  logical_power universal_power *
  page11_i254
#ISCELL
  standard offpage *
  page11_i255
#CELL
  pure_quanta q_res *
  page11_i256
#ISCELL
  standard offpage *
  page11_i38
#ISCELL
  standard offpage *
  page11_i42
#ISCELL
  logical_power vccaux15 *
  page11_i56
#ISCELL
  logical_power universal_gnd *
  page11_i58
#ISCELL
  standard offpage *
  page11_i63
#ISCELL
  standard offpage *
  page11_i72
#ISCELL
  standard offpage *
  page11_i76
#ISCELL
  mstr_misc dns *
  *
#ISCELL
  pure_quanta quanta_title_block_c *
  *
#ISCELL
  logical_power universal_power *
  page12_i1
#ISCELL
  standard offpage *
  page12_i10
#ISCELL
  standard offpage *
  page12_i103
#ISCELL
  standard offpage *
  page12_i104
#ISCELL
  standard offpage *
  page12_i105
#ISCELL
  standard offpage *
  page12_i106
#ISCELL
  standard tap *
  page12_i107
#ISCELL
  standard tap *
  page12_i108
#ISCELL
  standard tap *
  page12_i109
#ISCELL
  standard offpage *
  page12_i11
#ISCELL
  standard tap *
  page12_i110
#ISCELL
  standard tap *
  page12_i111
#ISCELL
  standard tap *
  page12_i112
#ISCELL
  standard tap *
  page12_i113
#ISCELL
  standard tap *
  page12_i114
#ISCELL
  standard tap *
  page12_i115
#ISCELL
  standard tap *
  page12_i116
#ISCELL
  standard tap *
  page12_i117
#ISCELL
  standard tap *
  page12_i118
#ISCELL
  standard offpage *
  page12_i119
#ISCELL
  standard offpage *
  page12_i12
#ISCELL
  standard offpage *
  page12_i120
#ISCELL
  standard offpage *
  page12_i121
#ISCELL
  standard offpage *
  page12_i123
#ISCELL
  standard offpage *
  page12_i124
#ISCELL
  standard offpage *
  page12_i125
#ISCELL
  standard offpage *
  page12_i126
#ISCELL
  standard offpage *
  page12_i128
#ISCELL
  standard offpage *
  page12_i129
#ISCELL
  standard offpage *
  page12_i134
#ISCELL
  standard offpage *
  page12_i135
#ISCELL
  standard offpage *
  page12_i136
#ISCELL
  standard offpage *
  page12_i137
#ISCELL
  standard offpage *
  page12_i138
#ISCELL
  standard offpage *
  page12_i139
#ISCELL
  standard offpage *
  page12_i140
#ISCELL
  standard offpage *
  page12_i141
#ISCELL
  standard offpage *
  page12_i142
#ISCELL
  standard offpage *
  page12_i143
#ISCELL
  standard offpage *
  page12_i144
#ISCELL
  standard offpage *
  page12_i145
#ISCELL
  standard offpage *
  page12_i146
#ISCELL
  standard offpage *
  page12_i147
#ISCELL
  standard offpage *
  page12_i148
#ISCELL
  standard offpage *
  page12_i149
#ISCELL
  standard tap *
  page12_i150
#ISCELL
  standard tap *
  page12_i151
#CELL
  pure_quanta q_cap *
  page12_i152
#CELL
  pure_quanta q_cap *
  page12_i153
#ISCELL
  standard offpage *
  page12_i154
#ISCELL
  standard offpage *
  page12_i155
#ISCELL
  standard offpage *
  page12_i156
#CELL
  pure_quanta q_res *
  page12_i2
#ISCELL
  standard offpage *
  page12_i21
#CELL
  pure_quanta q_res *
  page12_i235
#CELL
  pure_quanta q_res *
  page12_i236
#CELL
  pure_quanta q_cap *
  page12_i24
#CELL
  pure_quanta q_res *
  page12_i244
#CELL
  pure_quanta q_res *
  page12_i245
#ISCELL
  standard offpage *
  page12_i246
#ISCELL
  standard offpage *
  page12_i247
#CELL
  pure_quanta q_res *
  page12_i248
#CELL
  pure_quanta q_res *
  page12_i249
#ISCELL
  logical_power universal_power *
  page12_i25
#ISCELL
  standard offpage *
  page12_i250
#ISCELL
  standard offpage *
  page12_i251
#CELL
  pure_quanta q_res *
  page12_i252
#CELL
  pure_quanta q_res *
  page12_i253
#CELL
  pure_quanta q_res *
  page12_i254
#CELL
  pure_quanta q_res *
  page12_i255
#ISCELL
  logical_power universal_gnd *
  page12_i26
#ISCELL
  standard offpage *
  page12_i260
#ISCELL
  standard offpage *
  page12_i261
#ISCELL
  standard offpage *
  page12_i262
#ISCELL
  standard offpage *
  page12_i267
#CELL
  pure_quanta q_res *
  page12_i268
#ISCELL
  standard offpage *
  page12_i269
#ISCELL
  standard offpage *
  page12_i271
#ISCELL
  standard offpage *
  page12_i272
#CELL
  pure_quanta q_res *
  page12_i274
#CELL
  pure_quanta q_res *
  page12_i275
#CELL
  pure_quanta q_res *
  page12_i276
#CELL
  pure_quanta q_res *
  page12_i277
#CELL
  pure_quanta q_cap *
  page12_i28
#ISCELL
  standard offpage *
  page12_i282
#ISCELL
  standard offpage *
  page12_i283
#ISCELL
  standard offpage *
  page12_i284
#ISCELL
  standard offpage *
  page12_i285
#CELL
  pure_quanta q_res *
  page12_i3
#ISCELL
  standard offpage *
  page12_i310
#ISCELL
  standard offpage *
  page12_i311
#ISCELL
  standard offpage *
  page12_i312
#ISCELL
  standard offpage *
  page12_i313
#CELL
  pure_quanta q_res *
  page12_i314
#CELL
  pure_quanta q_res *
  page12_i315
#CELL
  pure_quanta q_res *
  page12_i316
#CELL
  pure_quanta q_res *
  page12_i317
#CELL
  pure_quanta q_res *
  page12_i318
#CELL
  pure_quanta q_res *
  page12_i319
#CELL
  pure_quanta q_res *
  page12_i320
#CELL
  pure_quanta q_res *
  page12_i321
#ISCELL
  standard offpage *
  page12_i322
#ISCELL
  standard offpage *
  page12_i323
#ISCELL
  standard offpage *
  page12_i324
#ISCELL
  standard offpage *
  page12_i325
#ISCELL
  standard offpage *
  page12_i326
#ISCELL
  standard offpage *
  page12_i329
#CELL
  pure_quanta q_res *
  page12_i33
#ISCELL
  standard offpage *
  page12_i332
#ISCELL
  standard offpage *
  page12_i333
#ISCELL
  standard offpage *
  page12_i334
#ISCELL
  standard offpage *
  page12_i335
#ISCELL
  standard offpage *
  page12_i336
#ISCELL
  standard offpage *
  page12_i337
#ISCELL
  standard offpage *
  page12_i338
#ISCELL
  standard offpage *
  page12_i339
#CELL
  pure_quanta q_res *
  page12_i34
#ISCELL
  standard offpage *
  page12_i340
#ISCELL
  logical_power universal_power *
  page12_i349
#ISCELL
  logical_power universal_gnd *
  page12_i35
#CELL
  pure_quanta q_res *
  page12_i350
#ISCELL
  standard offpage *
  page12_i351
#CELL
  pure_quanta q_res *
  page12_i353
#CELL
  pure_quanta q_res *
  page12_i354
#ISCELL
  standard offpage *
  page12_i355
#ISCELL
  standard offpage *
  page12_i36
#ISCELL
  standard offpage *
  page12_i37
#CELL
  pure_quanta q_res *
  page12_i379
#ISCELL
  standard offpage *
  page12_i38
#CELL
  pure_quanta q_res *
  page12_i380
#CELL
  pure_quanta q_res *
  page12_i381
#CELL
  pure_quanta q_res *
  page12_i382
#ISCELL
  standard offpage *
  page12_i383
#ISCELL
  standard offpage *
  page12_i384
#CELL
  pure_quanta q_res *
  page12_i385
#CELL
  pure_quanta q_res *
  page12_i386
#ISCELL
  logical_power universal_gnd *
  page12_i389
#ISCELL
  standard offpage *
  page12_i39
#CELL
  pure_quanta q_res *
  page12_i390
#CELL
  pure_quanta q_res *
  page12_i391
#CELL
  pure_quanta q_res *
  page12_i392
#CELL
  pure_quanta q_res *
  page12_i393
#ISCELL
  standard offpage *
  page12_i397
#CELL
  pure_quanta q_res *
  page12_i4
#ISCELL
  standard offpage *
  page12_i40
#ISCELL
  standard offpage *
  page12_i400
#ISCELL
  standard offpage *
  page12_i41
#ISCELL
  standard offpage *
  page12_i410
#ISCELL
  standard offpage *
  page12_i42
#CELL
  pure_quanta q_cap *
  page12_i428
#CELL
  pure_quanta q_cap *
  page12_i429
#ISCELL
  standard offpage *
  page12_i43
#ISCELL
  standard offpage *
  page12_i430
#ISCELL
  standard offpage *
  page12_i431
#ISCELL
  standard offpage *
  page12_i432
#ISCELL
  standard offpage *
  page12_i433
#ISCELL
  standard offpage *
  page12_i434
#ISCELL
  standard offpage *
  page12_i435
#CELL
  pure_quanta ast2600a3gp *
  page12_i436
#ISCELL
  standard offpage *
  page12_i439
#ISCELL
  standard offpage *
  page12_i44
#ISCELL
  standard offpage *
  page12_i440
#CELL
  pure_quanta q_res *
  page12_i441
#CELL
  pure_quanta q_res *
  page12_i442
#CELL
  pure_quanta q_res *
  page12_i443
#CELL
  pure_quanta q_res *
  page12_i444
#CELL
  pure_quanta q_res *
  page12_i445
#ISCELL
  standard offpage *
  page12_i446
#CELL
  pure_quanta q_res *
  page12_i447
#CELL
  pure_quanta q_cap *
  page12_i448
#ISCELL
  standard offpage *
  page12_i449
#CELL
  pure_quanta q_res *
  page12_i454
#ISCELL
  logical_power vccaux15 *
  page12_i455
#CELL
  pure_quanta q_res *
  page12_i456
#ISCELL
  logical_power universal_gnd *
  page12_i457
#CELL
  pure_quanta q_res *
  page12_i458
#CELL
  pure_quanta q_res *
  page12_i46
#ISCELL
  standard offpage *
  page12_i460
#ISCELL
  standard offpage *
  page12_i461
#ISCELL
  standard tap *
  page12_i47
#CELL
  pure_quanta q_res *
  page12_i473
#CELL
  pure_quanta q_res *
  page12_i474
#ISCELL
  standard offpage *
  page12_i477
#ISCELL
  standard offpage *
  page12_i478
#ISCELL
  standard tap *
  page12_i48
#ISCELL
  standard offpage *
  page12_i485
#ISCELL
  standard offpage *
  page12_i487
#ISCELL
  standard offpage *
  page12_i488
#ISCELL
  standard offpage *
  page12_i489
#ISCELL
  standard tap *
  page12_i49
#ISCELL
  standard offpage *
  page12_i490
#ISCELL
  standard offpage *
  page12_i493
#ISCELL
  standard offpage *
  page12_i494
#ISCELL
  standard offpage *
  page12_i495
#ISCELL
  standard offpage *
  page12_i496
#ISCELL
  standard offpage *
  page12_i499
#ISCELL
  logical_power universal_gnd *
  page12_i50
#ISCELL
  standard offpage *
  page12_i500
#ISCELL
  standard offpage *
  page12_i503
#ISCELL
  standard offpage *
  page12_i504
#ISCELL
  standard offpage *
  page12_i505
#ISCELL
  standard offpage *
  page12_i506
#ISCELL
  standard offpage *
  page12_i507
#CELL
  pure_quanta q_res *
  page12_i508
#ISCELL
  logical_power universal_gnd *
  page12_i509
#ISCELL
  standard offpage *
  page12_i51
#CELL
  pure_quanta q_res *
  page12_i510
#CELL
  pure_quanta q_res *
  page12_i512
#CELL
  pure_quanta q_res *
  page12_i513
#ISCELL
  standard offpage *
  page12_i52
#CELL
  pure_quanta q_res *
  page12_i53
#ISCELL
  standard offpage *
  page12_i54
#ISCELL
  standard offpage *
  page12_i55
#ISCELL
  standard offpage *
  page12_i56
#ISCELL
  standard offpage *
  page12_i57
#ISCELL
  standard tap *
  page12_i58
#ISCELL
  standard tap *
  page12_i59
#ISCELL
  standard tap *
  page12_i60
#ISCELL
  standard tap *
  page12_i61
#ISCELL
  standard tap *
  page12_i62
#ISCELL
  standard tap *
  page12_i63
#ISCELL
  standard tap *
  page12_i64
#ISCELL
  standard tap *
  page12_i65
#ISCELL
  standard tap *
  page12_i66
#ISCELL
  standard tap *
  page12_i67
#ISCELL
  standard tap *
  page12_i68
#ISCELL
  standard tap *
  page12_i69
#ISCELL
  standard tap *
  page12_i70
#ISCELL
  standard offpage *
  page12_i8
#CELL
  pure_quanta q_res *
  page12_i88
#CELL
  pure_quanta q_res *
  page12_i89
#ISCELL
  standard offpage *
  page12_i9
#CELL
  pure_quanta q_res *
  page12_i97
#CELL
  pure_quanta q_res *
  page12_i98
#ISCELL
  logical_power bom_note *
  *
#ISCELL
  mstr_misc dns *
  *
#ISCELL
  pure_quanta quanta_title_block_c *
  *
#ISCELL
  logical_power universal_power *
  page13_i1
#ISCELL
  standard offpage *
  page13_i10
#ISCELL
  standard offpage *
  page13_i103
#ISCELL
  standard offpage *
  page13_i104
#ISCELL
  standard offpage *
  page13_i105
#ISCELL
  standard offpage *
  page13_i107
#ISCELL
  standard offpage *
  page13_i108
#ISCELL
  standard offpage *
  page13_i109
#ISCELL
  standard offpage *
  page13_i11
#ISCELL
  standard offpage *
  page13_i110
#ISCELL
  standard offpage *
  page13_i111
#ISCELL
  standard offpage *
  page13_i112
#ISCELL
  standard offpage *
  page13_i113
#ISCELL
  standard offpage *
  page13_i114
#ISCELL
  standard offpage *
  page13_i115
#ISCELL
  standard offpage *
  page13_i12
#ISCELL
  standard offpage *
  page13_i13
#CELL
  pure_quanta q_res *
  page13_i133
#ISCELL
  standard offpage *
  page13_i134
#ISCELL
  standard offpage *
  page13_i14
#ISCELL
  standard offpage *
  page13_i143
#ISCELL
  standard offpage *
  page13_i144
#ISCELL
  standard offpage *
  page13_i145
#ISCELL
  standard offpage *
  page13_i146
#ISCELL
  standard offpage *
  page13_i147
#ISCELL
  standard offpage *
  page13_i15
#ISCELL
  standard offpage *
  page13_i153
#CELL
  pure_quanta q_res *
  page13_i156
#ISCELL
  standard offpage *
  page13_i157
#ISCELL
  standard offpage *
  page13_i158
#CELL
  pure_quanta q_res *
  page13_i159
#CELL
  pure_quanta q_res *
  page13_i16
#CELL
  pure_quanta q_res *
  page13_i17
#CELL
  pure_quanta q_res *
  page13_i18
#ISCELL
  standard offpage *
  page13_i182
#ISCELL
  standard offpage *
  page13_i183
#CELL
  pure_quanta q_res *
  page13_i184
#CELL
  pure_quanta q_res *
  page13_i185
#CELL
  pure_quanta q_res *
  page13_i186
#CELL
  pure_quanta q_res *
  page13_i187
#CELL
  pure_quanta q_res *
  page13_i188
#ISCELL
  standard offpage *
  page13_i189
#ISCELL
  standard offpage *
  page13_i190
#ISCELL
  standard offpage *
  page13_i191
#ISCELL
  standard offpage *
  page13_i192
#ISCELL
  standard offpage *
  page13_i193
#ISCELL
  logical_power universal_power *
  page13_i194
#CELL
  pure_quanta q_res *
  page13_i198
#ISCELL
  standard offpage *
  page13_i199
#ISCELL
  logical_power universal_power *
  page13_i2
#CELL
  pure_quanta q_res *
  page13_i200
#ISCELL
  standard offpage *
  page13_i202
#ISCELL
  standard offpage *
  page13_i203
#CELL
  pure_quanta q_res *
  page13_i204
#ISCELL
  standard offpage *
  page13_i205
#ISCELL
  standard offpage *
  page13_i207
#CELL
  pure_quanta q_res *
  page13_i208
#ISCELL
  standard offpage *
  page13_i209
#ISCELL
  standard offpage *
  page13_i212
#CELL
  pure_quanta q_res *
  page13_i213
#ISCELL
  standard offpage *
  page13_i214
#CELL
  pure_quanta q_res *
  page13_i215
#CELL
  pure_quanta q_res *
  page13_i217
#CELL
  pure_quanta q_res *
  page13_i218
#ISCELL
  standard offpage *
  page13_i219
#ISCELL
  standard offpage *
  page13_i22
#CELL
  pure_quanta q_res *
  page13_i220
#CELL
  pure_quanta q_res *
  page13_i223
#ISCELL
  standard offpage *
  page13_i224
#CELL
  pure_quanta q_res *
  page13_i225
#ISCELL
  standard offpage *
  page13_i226
#CELL
  pure_quanta q_res *
  page13_i227
#ISCELL
  standard offpage *
  page13_i229
#ISCELL
  standard offpage *
  page13_i236
#CELL
  pure_quanta q_res *
  page13_i239
#ISCELL
  standard offpage *
  page13_i24
#ISCELL
  standard offpage *
  page13_i240
#ISCELL
  standard offpage *
  page13_i241
#ISCELL
  standard offpage *
  page13_i242
#ISCELL
  standard offpage *
  page13_i243
#ISCELL
  standard offpage *
  page13_i244
#CELL
  pure_quanta q_res *
  page13_i245
#CELL
  pure_quanta q_res *
  page13_i246
#CELL
  pure_quanta q_res *
  page13_i247
#CELL
  pure_quanta q_res *
  page13_i248
#ISCELL
  standard offpage *
  page13_i26
#CELL
  pure_quanta q_res *
  page13_i266
#ISCELL
  standard offpage *
  page13_i27
#ISCELL
  standard offpage *
  page13_i274
#ISCELL
  standard offpage *
  page13_i275
#CELL
  pure_quanta q_res *
  page13_i278
#CELL
  pure_quanta q_res *
  page13_i279
#ISCELL
  logical_power universal_gnd *
  page13_i28
#ISCELL
  logical_power universal_power *
  page13_i282
#ISCELL
  standard offpage *
  page13_i283
#ISCELL
  standard offpage *
  page13_i284
#CELL
  pure_quanta q_res *
  page13_i286
#ISCELL
  standard offpage *
  page13_i289
#CELL
  pure_quanta q_cap *
  page13_i29
#ISCELL
  standard offpage *
  page13_i290
#CELL
  pure_quanta q_res *
  page13_i295
#ISCELL
  standard offpage *
  page13_i296
#ISCELL
  standard offpage *
  page13_i297
#ISCELL
  standard offpage *
  page13_i298
#CELL
  pure_quanta q_res *
  page13_i299
#CELL
  pure_quanta q_res *
  page13_i3
#CELL
  pure_quanta q_cap *
  page13_i30
#CELL
  pure_quanta q_res *
  page13_i300
#CELL
  pure_quanta q_res *
  page13_i301
#ISCELL
  standard offpage *
  page13_i303
#CELL
  pure_quanta q_res *
  page13_i306
#ISCELL
  standard offpage *
  page13_i307
#ISCELL
  standard offpage *
  page13_i308
#ISCELL
  standard offpage *
  page13_i309
#CELL
  pure_quanta q_cap *
  page13_i31
#CELL
  pure_quanta q_res *
  page13_i312
#ISCELL
  standard offpage *
  page13_i313
#CELL
  pure_quanta q_res *
  page13_i319
#CELL
  pure_quanta q_cap *
  page13_i32
#ISCELL
  standard offpage *
  page13_i320
#CELL
  pure_quanta q_res *
  page13_i33
#ISCELL
  standard offpage *
  page13_i333
#CELL
  pure_quanta q_res *
  page13_i335
#ISCELL
  standard offpage *
  page13_i336
#CELL
  pure_quanta q_res *
  page13_i337
#ISCELL
  standard offpage *
  page13_i338
#CELL
  pure_quanta q_res *
  page13_i339
#ISCELL
  logical_power universal_power *
  page13_i34
#CELL
  pure_quanta q_res *
  page13_i340
#ISCELL
  logical_power universal_gnd *
  page13_i341
#CELL
  pure_quanta q_res *
  page13_i344
#ISCELL
  standard offpage *
  page13_i345
#CELL
  pure_quanta q_res *
  page13_i349
#ISCELL
  logical_power universal_power *
  page13_i35
#CELL
  pure_quanta q_res *
  page13_i350
#CELL
  pure_quanta q_res *
  page13_i351
#ISCELL
  standard offpage *
  page13_i352
#CELL
  pure_quanta q_res *
  page13_i353
#ISCELL
  logical_power universal_power *
  page13_i355
#CELL
  pure_quanta q_res *
  page13_i356
#ISCELL
  standard offpage *
  page13_i358
#ISCELL
  standard offpage *
  page13_i359
#CELL
  pure_quanta q_res *
  page13_i360
#CELL
  pure_quanta ast2600a3gp *
  page13_i363
#ISCELL
  standard offpage *
  page13_i364
#CELL
  pure_quanta q_res *
  page13_i365
#ISCELL
  standard offpage *
  page13_i368
#ISCELL
  standard offpage *
  page13_i369
#ISCELL
  standard offpage *
  page13_i370
#ISCELL
  standard offpage *
  page13_i371
#ISCELL
  standard offpage *
  page13_i372
#CELL
  pure_quanta q_res *
  page13_i373
#CELL
  pure_quanta q_res *
  page13_i374
#CELL
  pure_quanta q_res *
  page13_i381
#CELL
  pure_quanta q_res *
  page13_i382
#CELL
  pure_quanta q_res *
  page13_i383
#CELL
  pure_quanta q_res *
  page13_i384
#ISCELL
  standard offpage *
  page13_i392
#ISCELL
  standard offpage *
  page13_i393
#ISCELL
  standard offpage *
  page13_i394
#ISCELL
  standard offpage *
  page13_i395
#ISCELL
  standard offpage *
  page13_i396
#CELL
  pure_quanta q_res *
  page13_i398
#CELL
  pure_quanta q_res *
  page13_i399
#CELL
  pure_quanta q_res *
  page13_i4
#CELL
  pure_quanta q_res *
  page13_i400
#CELL
  pure_quanta q_res *
  page13_i402
#ISCELL
  standard offpage *
  page13_i403
#ISCELL
  standard offpage *
  page13_i404
#ISCELL
  standard offpage *
  page13_i405
#ISCELL
  standard offpage *
  page13_i406
#CELL
  pure_quanta q_res *
  page13_i407
#ISCELL
  standard offpage *
  page13_i409
#ISCELL
  standard offpage *
  page13_i413
#ISCELL
  standard offpage *
  page13_i414
#ISCELL
  standard offpage *
  page13_i415
#ISCELL
  standard offpage *
  page13_i417
#CELL
  pure_quanta q_res *
  page13_i419
#ISCELL
  standard offpage *
  page13_i420
#CELL
  pure_quanta q_res *
  page13_i421
#ISCELL
  standard offpage *
  page13_i422
#ISCELL
  standard offpage *
  page13_i426
#CELL
  pure_quanta q_res *
  page13_i427
#ISCELL
  standard offpage *
  page13_i428
#ISCELL
  standard offpage *
  page13_i429
#CELL
  pure_quanta q_res *
  page13_i430
#CELL
  pure_quanta q_res *
  page13_i431
#CELL
  pure_quanta q_res *
  page13_i432
#ISCELL
  standard offpage *
  page13_i433
#ISCELL
  standard offpage *
  page13_i434
#CELL
  pure_quanta 74lvc1g66gv *
  page13_i435
#ISCELL
  standard offpage *
  page13_i436
#ISCELL
  logical_power universal_gnd *
  page13_i439
#CELL
  pure_quanta q_cap *
  page13_i440
#ISCELL
  logical_power vccaux15 *
  page13_i441
#ISCELL
  logical_power universal_gnd *
  page13_i442
#ISCELL
  standard offpage *
  page13_i443
#ISCELL
  standard offpage *
  page13_i446
#CELL
  pure_quanta q_res *
  page13_i447
#CELL
  pure_quanta q_res *
  page13_i448
#CELL
  pure_quanta q_res *
  page13_i449
#CELL
  pure_quanta q_res *
  page13_i451
#CELL
  pure_quanta q_res *
  page13_i452
#CELL
  pure_quanta q_res *
  page13_i453
#CELL
  pure_quanta q_led *
  page13_i46
#ISCELL
  standard offpage *
  page13_i48
#CELL
  pure_quanta q_res *
  page13_i5
#CELL
  pure_quanta q_res *
  page13_i50
#ISCELL
  standard offpage *
  page13_i55
#ISCELL
  logical_power universal_power *
  page13_i6
#CELL
  pure_quanta q_res *
  page13_i67
#ISCELL
  standard offpage *
  page13_i69
#ISCELL
  standard offpage *
  page13_i7
#ISCELL
  standard offpage *
  page13_i76
#ISCELL
  standard offpage *
  page13_i77
#ISCELL
  standard offpage *
  page13_i78
#ISCELL
  standard offpage *
  page13_i79
#ISCELL
  standard offpage *
  page13_i8
#ISCELL
  standard offpage *
  page13_i80
#CELL
  pure_quanta q_res *
  page13_i87
#ISCELL
  standard offpage *
  page13_i9
#ISCELL
  standard offpage *
  page13_i91
#CELL
  pure_quanta q_res *
  page13_i94
#CELL
  pure_quanta q_res *
  page13_i95
#CELL
  pure_quanta q_res *
  page13_i96
#ISCELL
  standard offpage *
  page13_i97
#ISCELL
  logical_power design_note *
  *
#ISCELL
  mstr_misc dns *
  *
#ISCELL
  pure_quanta quanta_title_block_c *
  *
#ISCELL
  standard offpage *
  page14_i1
#CELL
  pure_quanta ast2600a3gp *
  page14_i149
#ISCELL
  logical_power universal_gnd *
  page14_i162
#CELL
  pure_quanta q_res *
  page14_i163
#CELL
  pure_quanta q_res *
  page14_i164
#CELL
  pure_quanta q_res *
  page14_i165
#CELL
  pure_quanta q_res *
  page14_i166
#ISCELL
  standard offpage *
  page14_i167
#ISCELL
  standard offpage *
  page14_i168
#CELL
  pure_quanta q_res *
  page14_i171
#CELL
  pure_quanta q_res *
  page14_i172
#CELL
  pure_quanta q_res *
  page14_i173
#CELL
  pure_quanta q_res *
  page14_i174
#CELL
  pure_quanta q_res *
  page14_i183
#ISCELL
  standard offpage *
  page14_i184
#ISCELL
  standard offpage *
  page14_i185
#ISCELL
  standard offpage *
  page14_i186
#ISCELL
  standard offpage *
  page14_i187
#CELL
  pure_quanta q_res *
  page14_i188
#CELL
  pure_quanta q_res *
  page14_i189
#CELL
  pure_quanta q_res *
  page14_i190
#ISCELL
  standard offpage *
  page14_i2
#ISCELL
  logical_power universal_gnd *
  page14_i208
#ISCELL
  standard offpage *
  page14_i21
#ISCELL
  logical_power universal_power *
  page14_i218
#ISCELL
  logical_power universal_power *
  page14_i219
#ISCELL
  standard offpage *
  page14_i22
#CELL
  pure_quanta q_res *
  page14_i220
#CELL
  pure_quanta q_res *
  page14_i221
#CELL
  pure_quanta q_res *
  page14_i222
#CELL
  pure_quanta q_res *
  page14_i223
#CELL
  pure_quanta q_res *
  page14_i224
#CELL
  pure_quanta q_res *
  page14_i225
#ISCELL
  standard offpage *
  page14_i228
#CELL
  pure_quanta q_res *
  page14_i229
#ISCELL
  logical_power universal_power *
  page14_i230
#CELL
  pure_quanta q_res *
  page14_i231
#CELL
  pure_quanta q_res *
  page14_i232
#CELL
  pure_quanta q_res *
  page14_i233
#CELL
  pure_quanta q_res *
  page14_i234
#CELL
  pure_quanta q_res *
  page14_i235
#CELL
  pure_quanta q_res *
  page14_i236
#CELL
  pure_quanta q_res *
  page14_i237
#CELL
  pure_quanta q_res *
  page14_i238
#CELL
  pure_quanta q_res *
  page14_i239
#ISCELL
  standard offpage *
  page14_i3
#ISCELL
  standard offpage *
  page14_i4
#ISCELL
  standard offpage *
  page14_i45
#ISCELL
  standard offpage *
  page14_i46
#ISCELL
  standard offpage *
  page14_i47
#ISCELL
  standard offpage *
  page14_i48
#ISCELL
  standard offpage *
  page14_i87
#ISCELL
  standard offpage *
  page14_i88
#ISCELL
  logical_power universal_power *
  page14_i9
#ISCELL
  logical_power design_note *
  *
#ISCELL
  mstr_misc dns *
  *
#ISCELL
  pure_quanta quanta_title_block_c *
  *
#ISCELL
  logical_power universal_power *
  page15_i1
#ISCELL
  standard offpage *
  page15_i101
#ISCELL
  standard offpage *
  page15_i102
#ISCELL
  standard offpage *
  page15_i103
#CELL
  pure_quanta q_cap *
  page15_i117
#ISCELL
  logical_power universal_gnd *
  page15_i118
#CELL
  pure_quanta q_cap *
  page15_i119
#ISCELL
  standard offpage *
  page15_i120
#ISCELL
  standard offpage *
  page15_i125
#ISCELL
  standard offpage *
  page15_i126
#CELL
  pure_quanta q_res *
  page15_i128
#ISCELL
  standard offpage *
  page15_i130
#ISCELL
  standard offpage *
  page15_i131
#ISCELL
  standard offpage *
  page15_i132
#CELL
  pure_quanta q_res *
  page15_i133
#CELL
  pure_quanta q_res *
  page15_i134
#ISCELL
  standard offpage *
  page15_i135
#ISCELL
  standard offpage *
  page15_i136
#ISCELL
  standard offpage *
  page15_i137
#ISCELL
  standard offpage *
  page15_i138
#ISCELL
  standard offpage *
  page15_i139
#CELL
  pure_quanta q_cap *
  page15_i14
#CELL
  pure_quanta q_res *
  page15_i140
#CELL
  pure_quanta q_res *
  page15_i141
#CELL
  pure_quanta q_res *
  page15_i142
#ISCELL
  standard offpage *
  page15_i143
#ISCELL
  standard offpage *
  page15_i144
#ISCELL
  standard offpage *
  page15_i145
#ISCELL
  standard offpage *
  page15_i146
#ISCELL
  standard offpage *
  page15_i147
#ISCELL
  logical_power universal_gnd *
  page15_i148
#CELL
  pure_quanta q_res *
  page15_i149
#ISCELL
  logical_power universal_gnd *
  page15_i15
#CELL
  pure_quanta q_res *
  page15_i150
#CELL
  pure_quanta q_res *
  page15_i151
#CELL
  pure_quanta q_res *
  page15_i152
#ISCELL
  logical_power universal_power *
  page15_i154
#ISCELL
  standard offpage *
  page15_i155
#ISCELL
  standard offpage *
  page15_i159
#CELL
  pure_quanta q_cap *
  page15_i16
#CELL
  pure_quanta q_res *
  page15_i168
#CELL
  pure_quanta q_res *
  page15_i169
#ISCELL
  logical_power universal_gnd *
  page15_i17
#ISCELL
  standard offpage *
  page15_i170
#ISCELL
  standard offpage *
  page15_i171
#CELL
  pure_quanta q_res *
  page15_i174
#ISCELL
  logical_power vccaux15 *
  page15_i175
#ISCELL
  standard offpage *
  page15_i176
#CELL
  pure_quanta mosfet_n_gsd *
  page15_i179
#ISCELL
  logical_power universal_power *
  page15_i18
#CELL
  pure_quanta q_cap *
  page15_i180
#CELL
  pure_quanta q_res *
  page15_i181
#CELL
  pure_quanta q_res *
  page15_i183
#CELL
  pure_quanta q_res *
  page15_i184
#ISCELL
  standard offpage *
  page15_i185
#ISCELL
  standard offpage *
  page15_i186
#ISCELL
  logical_power universal_gnd *
  page15_i188
#ISCELL
  logical_power universal_gnd *
  page15_i189
#CELL
  pure_quanta q_res *
  page15_i19
#ISCELL
  standard offpage *
  page15_i190
#ISCELL
  standard offpage *
  page15_i191
#ISCELL
  logical_power universal_power *
  page15_i194
#ISCELL
  logical_power vccaux15 *
  page15_i195
#ISCELL
  logical_power vccaux15 *
  page15_i196
#ISCELL
  logical_power vccaux15 *
  page15_i197
#ISCELL
  logical_power vccaux15 *
  page15_i199
#CELL
  pure_quanta q_res *
  page15_i2
#ISCELL
  logical_power vccaux15 *
  page15_i200
#CELL
  pure_quanta q_cap *
  page15_i201
#CELL
  pure_quanta q_res *
  page15_i202
#CELL
  pure_quanta q_res *
  page15_i203
#ISCELL
  logical_power universal_gnd *
  page15_i204
#ISCELL
  standard offpage *
  page15_i205
#ISCELL
  standard offpage *
  page15_i206
#CELL
  pure_quanta q_cap *
  page15_i207
#CELL
  pure_quanta q_res *
  page15_i21
#ISCELL
  standard offpage *
  page15_i210
#CELL
  pure_quanta q_res *
  page15_i211
#ISCELL
  logical_power universal_gnd *
  page15_i212
#ISCELL
  standard offpage *
  page15_i213
#CELL
  pure_quanta q_cap *
  page15_i215
#ISCELL
  logical_power universal_gnd *
  page15_i216
#ISCELL
  standard offpage *
  page15_i217
#CELL
  pure_quanta q_res *
  page15_i219
#ISCELL
  logical_power universal_power *
  page15_i22
#CELL
  pure_quanta q_res *
  page15_i220
#ISCELL
  logical_power universal_power *
  page15_i221
#ISCELL
  standard offpage *
  page15_i222
#CELL
  pure_quanta q_res *
  page15_i223
#ISCELL
  standard offpage *
  page15_i228
#ISCELL
  standard offpage *
  page15_i229
#ISCELL
  logical_power universal_gnd *
  page15_i23
#ISCELL
  standard offpage *
  page15_i234
#CELL
  pure_quanta q_cap *
  page15_i235
#CELL
  pure_quanta q_res *
  page15_i236
#ISCELL
  logical_power universal_gnd *
  page15_i237
#ISCELL
  standard offpage *
  page15_i238
#CELL
  pure_quanta q_cap *
  page15_i24
#CELL
  pure_quanta q_cap *
  page15_i240
#CELL
  pure_quanta q_res *
  page15_i242
#ISCELL
  logical_power universal_gnd *
  page15_i243
#CELL
  pure_quanta q_res *
  page15_i244
#CELL
  pure_quanta q_res *
  page15_i245
#ISCELL
  standard offpage *
  page15_i246
#CELL
  pure_quanta q_cap *
  page15_i247
#ISCELL
  logical_power universal_power *
  page15_i25
#ISCELL
  logical_power universal_gnd *
  page15_i251
#CELL
  pure_quanta q_res *
  page15_i252
#ISCELL
  standard offpage *
  page15_i254
#CELL
  pure_quanta q_res *
  page15_i255
#CELL
  pure_quanta q_cap *
  page15_i256
#ISCELL
  logical_power universal_gnd *
  page15_i257
#ISCELL
  standard offpage *
  page15_i258
#CELL
  pure_quanta q_cap *
  page15_i259
#ISCELL
  standard offpage *
  page15_i26
#CELL
  pure_quanta q_res *
  page15_i261
#CELL
  pure_quanta q_res *
  page15_i262
#ISCELL
  logical_power universal_gnd *
  page15_i263
#ISCELL
  logical_power universal_power *
  page15_i264
#ISCELL
  standard offpage *
  page15_i265
#ISCELL
  standard offpage *
  page15_i266
#ISCELL
  standard offpage *
  page15_i267
#ISCELL
  standard offpage *
  page15_i27
#ISCELL
  standard offpage *
  page15_i270
#ISCELL
  standard offpage *
  page15_i271
#ISCELL
  standard offpage *
  page15_i272
#ISCELL
  standard offpage *
  page15_i275
#ISCELL
  standard offpage *
  page15_i28
#ISCELL
  standard offpage *
  page15_i287
#CELL
  pure_quanta q_res *
  page15_i289
#ISCELL
  standard offpage *
  page15_i29
#ISCELL
  standard offpage *
  page15_i292
#ISCELL
  standard offpage *
  page15_i293
#ISCELL
  standard offpage *
  page15_i294
#ISCELL
  standard offpage *
  page15_i299
#ISCELL
  logical_power universal_power *
  page15_i3
#ISCELL
  standard offpage *
  page15_i300
#ISCELL
  standard offpage *
  page15_i301
#ISCELL
  standard offpage *
  page15_i302
#ISCELL
  standard offpage *
  page15_i303
#ISCELL
  standard offpage *
  page15_i306
#ISCELL
  standard offpage *
  page15_i309
#ISCELL
  logical_power universal_power *
  page15_i31
#ISCELL
  standard offpage *
  page15_i311
#ISCELL
  standard offpage *
  page15_i312
#ISCELL
  standard offpage *
  page15_i313
#ISCELL
  standard offpage *
  page15_i315
#ISCELL
  standard offpage *
  page15_i316
#ISCELL
  standard offpage *
  page15_i317
#CELL
  pure_quanta q_res *
  page15_i318
#ISCELL
  standard offpage *
  page15_i319
#CELL
  pure_quanta q_res *
  page15_i32
#CELL
  pure_quanta q_res *
  page15_i320
#CELL
  pure_quanta q_res *
  page15_i321
#ISCELL
  standard offpage *
  page15_i322
#ISCELL
  standard offpage *
  page15_i323
#CELL
  pure_quanta q_res *
  page15_i326
#ISCELL
  standard offpage *
  page15_i327
#ISCELL
  logical_power universal_power *
  page15_i33
#CELL
  pure_quanta q_res *
  page15_i330
#ISCELL
  standard offpage *
  page15_i331
#CELL
  pure_quanta q_res *
  page15_i34
#ISCELL
  standard offpage *
  page15_i344
#CELL
  pure_quanta q_res *
  page15_i345
#CELL
  pure_quanta q_res *
  page15_i346
#ISCELL
  standard offpage *
  page15_i347
#ISCELL
  logical_power universal_gnd *
  page15_i35
#CELL
  pure_quanta ast2600a3gp *
  page15_i350
#CELL
  pure_quanta q_res *
  page15_i351
#ISCELL
  standard offpage *
  page15_i352
#CELL
  pure_quanta q_res *
  page15_i353
#CELL
  pure_quanta q_res *
  page15_i354
#ISCELL
  logical_power universal_gnd *
  page15_i355
#ISCELL
  standard offpage *
  page15_i357
#CELL
  pure_quanta q_cap *
  page15_i36
#ISCELL
  standard offpage *
  page15_i366
#CELL
  pure_quanta q_res *
  page15_i367
#CELL
  pure_quanta q_cap *
  page15_i368
#CELL
  pure_quanta q_cap *
  page15_i369
#CELL
  pure_quanta q_cap *
  page15_i37
#ISCELL
  standard offpage *
  page15_i370
#ISCELL
  standard offpage *
  page15_i371
#ISCELL
  standard offpage *
  page15_i372
#ISCELL
  standard offpage *
  page15_i373
#ISCELL
  standard offpage *
  page15_i378
#ISCELL
  standard offpage *
  page15_i379
#ISCELL
  logical_power universal_power *
  page15_i38
#ISCELL
  standard offpage *
  page15_i383
#ISCELL
  standard offpage *
  page15_i385
#ISCELL
  standard offpage *
  page15_i386
#CELL
  pure_quanta q_res *
  page15_i387
#CELL
  pure_quanta q_res *
  page15_i389
#CELL
  pure_quanta osc4_7x25000018 *
  page15_i39
#ISCELL
  standard offpage *
  page15_i390
#CELL
  pure_quanta q_res *
  page15_i391
#ISCELL
  standard offpage *
  page15_i392
#CELL
  pure_quanta 74lvc1g08gw *
  page15_i393
#ISCELL
  standard offpage *
  page15_i395
#ISCELL
  logical_power universal_gnd *
  page15_i396
#ISCELL
  logical_power vccaux15 *
  page15_i397
#CELL
  pure_quanta q_cap *
  page15_i398
#ISCELL
  logical_power universal_gnd *
  page15_i399
#CELL
  pure_quanta q_res *
  page15_i4
#ISCELL
  logical_power universal_gnd *
  page15_i40
#ISCELL
  standard offpage *
  page15_i400
#ISCELL
  standard offpage *
  page15_i401
#CELL
  pure_quanta q_res *
  page15_i404
#CELL
  pure_quanta q_res *
  page15_i405
#CELL
  pure_quanta q_res *
  page15_i406
#CELL
  pure_quanta q_res *
  page15_i42
#ISCELL
  logical_power universal_gnd *
  page15_i46
#CELL
  pure_quanta q_res *
  page15_i47
#ISCELL
  standard offpage *
  page15_i48
#ISCELL
  standard offpage *
  page15_i49
#ISCELL
  standard offpage *
  page15_i5
#ISCELL
  standard offpage *
  page15_i50
#CELL
  pure_quanta q_res *
  page15_i51
#ISCELL
  logical_power universal_power *
  page15_i52
#ISCELL
  standard offpage *
  page15_i53
#ISCELL
  standard offpage *
  page15_i61
#ISCELL
  logical_power universal_power *
  page15_i64
#CELL
  pure_quanta q_inductor *
  page15_i65
#ISCELL
  logical_power universal_gnd *
  page15_i66
#CELL
  pure_quanta q_cap *
  page15_i68
#ISCELL
  standard offpage *
  page15_i80
#ISCELL
  logical_power universal_power *
  page15_i81
#CELL
  pure_quanta q_inductor *
  page15_i82
#ISCELL
  standard offpage *
  page15_i83
#ISCELL
  standard offpage *
  page15_i84
#ISCELL
  standard offpage *
  page15_i85
#ISCELL
  standard offpage *
  page15_i86
#ISCELL
  logical_power universal_gnd *
  page15_i87
#CELL
  pure_quanta q_cap *
  page15_i89
#ISCELL
  standard offpage *
  page15_i90
#CELL
  pure_quanta q_res *
  page15_i92
#CELL
  pure_quanta q_res *
  page15_i93
#ISCELL
  standard offpage *
  page15_i94
#ISCELL
  standard offpage *
  page15_i95
#ISCELL
  standard offpage *
  page15_i96
#ISCELL
  logical_power cad_note *
  *
#ISCELL
  pure_quanta quanta_title_block_c *
  *
#CELL
  pure_quanta q_cap *
  page16_i100
#ISCELL
  logical_power universal_gnd *
  page16_i105
#CELL
  pure_quanta q_cap *
  page16_i106
#ISCELL
  logical_power universal_power *
  page16_i107
#CELL
  pure_quanta q_cap *
  page16_i118
#CELL
  pure_quanta q_cap *
  page16_i119
#CELL
  pure_quanta q_cap *
  page16_i120
#ISCELL
  logical_power universal_gnd *
  page16_i121
#ISCELL
  logical_power universal_power *
  page16_i122
#CELL
  pure_quanta q_cap *
  page16_i123
#CELL
  pure_quanta q_cap *
  page16_i124
#ISCELL
  logical_power universal_power *
  page16_i125
#CELL
  pure_quanta q_cap *
  page16_i126
#CELL
  pure_quanta q_cap *
  page16_i127
#CELL
  pure_quanta q_cap *
  page16_i128
#CELL
  pure_quanta q_cap *
  page16_i129
#CELL
  pure_quanta q_cap *
  page16_i131
#CELL
  pure_quanta q_cap *
  page16_i132
#CELL
  pure_quanta q_cap *
  page16_i133
#ISCELL
  logical_power universal_gnd *
  page16_i134
#CELL
  pure_quanta q_cap *
  page16_i135
#ISCELL
  logical_power universal_gnd *
  page16_i137
#CELL
  pure_quanta q_cap *
  page16_i143
#ISCELL
  logical_power universal_power *
  page16_i144
#ISCELL
  logical_power universal_power *
  page16_i146
#CELL
  pure_quanta q_cap *
  page16_i147
#CELL
  pure_quanta q_cap *
  page16_i148
#CELL
  pure_quanta q_cap *
  page16_i149
#CELL
  pure_quanta q_cap *
  page16_i150
#CELL
  pure_quanta q_cap *
  page16_i151
#CELL
  pure_quanta q_cap *
  page16_i152
#CELL
  pure_quanta q_cap *
  page16_i153
#CELL
  pure_quanta q_cap *
  page16_i154
#CELL
  pure_quanta q_cap *
  page16_i155
#CELL
  pure_quanta q_cap *
  page16_i156
#CELL
  pure_quanta q_cap *
  page16_i157
#CELL
  pure_quanta q_cap *
  page16_i158
#CELL
  pure_quanta q_cap *
  page16_i159
#ISCELL
  logical_power universal_gnd *
  page16_i161
#CELL
  pure_quanta q_cap *
  page16_i162
#CELL
  pure_quanta q_cap *
  page16_i163
#CELL
  pure_quanta q_cap *
  page16_i164
#CELL
  pure_quanta q_cap *
  page16_i165
#CELL
  pure_quanta q_cap *
  page16_i166
#CELL
  pure_quanta q_cap *
  page16_i167
#CELL
  pure_quanta q_cap *
  page16_i168
#CELL
  pure_quanta q_cap *
  page16_i169
#ISCELL
  logical_power universal_power *
  page16_i170
#CELL
  pure_quanta q_cap *
  page16_i171
#ISCELL
  logical_power universal_power *
  page16_i172
#CELL
  pure_quanta q_cap *
  page16_i173
#CELL
  pure_quanta q_cap *
  page16_i174
#ISCELL
  logical_power universal_gnd *
  page16_i175
#ISCELL
  logical_power universal_power *
  page16_i178
#CELL
  pure_quanta q_cap *
  page16_i179
#CELL
  pure_quanta q_cap *
  page16_i180
#ISCELL
  standard offpage *
  page16_i182
#CELL
  pure_quanta q_cap *
  page16_i183
#ISCELL
  logical_power universal_gnd *
  page16_i184
#ISCELL
  standard offpage *
  page16_i185
#ISCELL
  standard offpage *
  page16_i186
#CELL
  pure_quanta q_res *
  page16_i187
#CELL
  pure_quanta ast2600a3gp *
  page16_i188
#CELL
  pure_quanta q_cap *
  page16_i189
#CELL
  pure_quanta q_cap *
  page16_i190
#CELL
  pure_quanta q_cap *
  page16_i191
#CELL
  pure_quanta q_cap *
  page16_i192
#CELL
  pure_quanta q_cap *
  page16_i193
#ISCELL
  logical_power universal_power *
  page16_i21
#ISCELL
  logical_power universal_power *
  page16_i22
#CELL
  pure_quanta q_cap *
  page16_i23
#CELL
  pure_quanta q_inductor *
  page16_i24
#ISCELL
  logical_power universal_power *
  page16_i25
#CELL
  pure_quanta q_inductor *
  page16_i29
#ISCELL
  logical_power universal_power *
  page16_i30
#CELL
  pure_quanta q_cap *
  page16_i31
#CELL
  pure_quanta q_cap *
  page16_i32
#CELL
  pure_quanta q_cap *
  page16_i33
#ISCELL
  logical_power universal_power *
  page16_i44
#CELL
  pure_quanta q_cap *
  page16_i46
#CELL
  pure_quanta q_inductor *
  page16_i47
#CELL
  pure_quanta q_cap *
  page16_i48
#CELL
  pure_quanta q_cap *
  page16_i49
#ISCELL
  logical_power universal_gnd *
  page16_i50
#CELL
  pure_quanta q_cap *
  page16_i51
#CELL
  pure_quanta q_cap *
  page16_i52
#CELL
  pure_quanta q_cap *
  page16_i53
#CELL
  pure_quanta q_cap *
  page16_i54
#CELL
  pure_quanta q_cap *
  page16_i55
#ISCELL
  logical_power universal_gnd *
  page16_i56
#CELL
  pure_quanta q_cap *
  page16_i57
#CELL
  pure_quanta q_cap *
  page16_i58
#CELL
  pure_quanta q_cap *
  page16_i59
#ISCELL
  logical_power universal_power *
  page16_i60
#ISCELL
  logical_power universal_power *
  page16_i61
#ISCELL
  logical_power universal_gnd *
  page16_i62
#ISCELL
  logical_power universal_power *
  page16_i63
#ISCELL
  logical_power universal_power *
  page16_i64
#ISCELL
  logical_power universal_power *
  page16_i65
#CELL
  pure_quanta q_cap *
  page16_i66
#ISCELL
  standard offpage *
  page16_i67
#ISCELL
  standard offpage *
  page16_i68
#ISCELL
  standard offpage *
  page16_i69
#ISCELL
  standard offpage *
  page16_i70
#CELL
  pure_quanta q_cap *
  page16_i79
#ISCELL
  logical_power universal_gnd *
  page16_i80
#CELL
  pure_quanta q_cap *
  page16_i81
#CELL
  pure_quanta q_cap *
  page16_i82
#ISCELL
  logical_power universal_gnd *
  page16_i83
#CELL
  pure_quanta q_res *
  page16_i86
#CELL
  pure_quanta q_res *
  page16_i87
#ISCELL
  standard offpage *
  page16_i88
#ISCELL
  standard offpage *
  page16_i89
#ISCELL
  standard offpage *
  page16_i90
#ISCELL
  standard offpage *
  page16_i91
#ISCELL
  standard offpage *
  page16_i92
#CELL
  pure_quanta q_cap *
  page16_i93
#ISCELL
  standard offpage *
  page16_i94
#ISCELL
  standard offpage *
  page16_i95
#ISCELL
  logical_power universal_gnd *
  page16_i96
#ISCELL
  logical_power universal_power *
  page16_i98
#CELL
  pure_quanta q_inductor *
  page16_i99
#ISCELL
  logical_power cad_note *
  *
#ISCELL
  mstr_misc dns *
  *
#ISCELL
  pure_quanta quanta_title_block_c *
  *
#ISCELL
  logical_power universal_gnd *
  page17_i1
#ISCELL
  logical_power universal_power *
  page17_i100
#CELL
  pure_quanta q_res *
  page17_i101
#ISCELL
  logical_power universal_power *
  page17_i102
#ISCELL
  logical_power universal_gnd *
  page17_i103
#CELL
  pure_quanta q_cap *
  page17_i104
#ISCELL
  logical_power universal_gnd *
  page17_i105
#CELL
  pure_quanta q_cap *
  page17_i106
#CELL
  pure_quanta q_cap *
  page17_i107
#CELL
  pure_quanta q_cap *
  page17_i108
#CELL
  pure_quanta q_cap *
  page17_i109
#CELL
  pure_quanta q_cap *
  page17_i110
#ISCELL
  logical_power universal_power *
  page17_i111
#ISCELL
  standard offpage *
  page17_i112
#ISCELL
  standard offpage *
  page17_i113
#ISCELL
  standard offpage *
  page17_i114
#ISCELL
  standard offpage *
  page17_i115
#CELL
  pure_quanta q_cap *
  page17_i118
#ISCELL
  standard offpage *
  page17_i119
#CELL
  pure_quanta q_inductor *
  page17_i120
#ISCELL
  logical_power universal_power *
  page17_i121
#CELL
  pure_quanta q_cap *
  page17_i122
#ISCELL
  logical_power universal_gnd *
  page17_i123
#CELL
  pure_quanta q_inductor *
  page17_i124
#ISCELL
  logical_power universal_power *
  page17_i125
#CELL
  pure_quanta q_cap *
  page17_i126
#ISCELL
  logical_power universal_gnd *
  page17_i127
#CELL
  pure_quanta q_cap *
  page17_i128
#ISCELL
  standard offpage *
  page17_i129
#ISCELL
  logical_power universal_power *
  page17_i130
#CELL
  pure_quanta q_res *
  page17_i131
#ISCELL
  logical_power universal_power *
  page17_i132
#CELL
  pure_quanta q_cap *
  page17_i133
#ISCELL
  logical_power universal_gnd *
  page17_i134
#CELL
  pure_quanta q_cap *
  page17_i135
#CELL
  pure_quanta q_res *
  page17_i136
#ISCELL
  logical_power universal_power *
  page17_i137
#ISCELL
  standard offpage *
  page17_i138
#CELL
  pure_quanta q_cap *
  page17_i139
#ISCELL
  logical_power universal_gnd *
  page17_i140
#CELL
  pure_quanta q_cap *
  page17_i141
#CELL
  pure_quanta q_inductor *
  page17_i142
#ISCELL
  logical_power universal_power *
  page17_i143
#ISCELL
  standard offpage *
  page17_i144
#CELL
  pure_quanta q_cap *
  page17_i145
#CELL
  pure_quanta q_inductor *
  page17_i146
#ISCELL
  logical_power universal_power *
  page17_i147
#CELL
  pure_quanta q_cap *
  page17_i148
#ISCELL
  logical_power universal_gnd *
  page17_i149
#ISCELL
  standard offpage *
  page17_i150
#CELL
  pure_quanta q_cap *
  page17_i151
#ISCELL
  logical_power universal_gnd *
  page17_i152
#CELL
  pure_quanta q_cap *
  page17_i153
#CELL
  pure_quanta q_inductor *
  page17_i154
#ISCELL
  logical_power universal_power *
  page17_i155
#ISCELL
  standard offpage *
  page17_i156
#CELL
  pure_quanta q_cap *
  page17_i157
#CELL
  pure_quanta q_inductor *
  page17_i158
#ISCELL
  logical_power universal_power *
  page17_i159
#CELL
  pure_quanta q_cap *
  page17_i160
#ISCELL
  logical_power universal_gnd *
  page17_i161
#ISCELL
  standard offpage *
  page17_i162
#CELL
  pure_quanta q_cap *
  page17_i163
#ISCELL
  logical_power universal_gnd *
  page17_i164
#CELL
  pure_quanta q_cap *
  page17_i165
#CELL
  pure_quanta q_inductor *
  page17_i166
#ISCELL
  logical_power universal_power *
  page17_i167
#ISCELL
  standard offpage *
  page17_i168
#CELL
  pure_quanta q_cap *
  page17_i169
#CELL
  pure_quanta q_inductor *
  page17_i170
#ISCELL
  logical_power universal_power *
  page17_i171
#ISCELL
  logical_power universal_gnd *
  page17_i172
#CELL
  pure_quanta q_cap *
  page17_i173
#ISCELL
  logical_power universal_power *
  page17_i174
#CELL
  pure_quanta q_inductor *
  page17_i176
#CELL
  pure_quanta q_cap *
  page17_i178
#ISCELL
  logical_power universal_gnd *
  page17_i179
#CELL
  pure_quanta q_cap *
  page17_i180
#ISCELL
  logical_power universal_gnd *
  page17_i181
#ISCELL
  logical_power universal_gnd *
  page17_i2
#CELL
  pure_quanta mosfet_n_gsd *
  page17_i227
#CELL
  pure_quanta q_res *
  page17_i228
#ISCELL
  standard offpage *
  page17_i229
#CELL
  pure_quanta q_res *
  page17_i230
#ISCELL
  logical_power universal_gnd *
  page17_i232
#ISCELL
  logical_power universal_gnd *
  page17_i233
#CELL
  pure_quanta q_cap *
  page17_i234
#ISCELL
  logical_power universal_power *
  page17_i236
#CELL
  pure_quanta q_cap *
  page17_i239
#ISCELL
  logical_power universal_gnd *
  page17_i240
#ISCELL
  standard offpage *
  page17_i248
#ISCELL
  standard offpage *
  page17_i249
#CELL
  pure_quanta q_cap *
  page17_i250
#ISCELL
  logical_power universal_gnd *
  page17_i251
#CELL
  pure_quanta q_cap *
  page17_i252
#CELL
  pure_quanta q_cap *
  page17_i253
#ISCELL
  logical_power universal_gnd *
  page17_i254
#CELL
  pure_quanta q_cap *
  page17_i255
#CELL
  pure_quanta q_res *
  page17_i256
#CELL
  pure_quanta q_res *
  page17_i259
#CELL
  pure_quanta q_res *
  page17_i260
#ISCELL
  logical_power universal_power *
  page17_i261
#ISCELL
  logical_power universal_power *
  page17_i262
#CELL
  pure_quanta q_res *
  page17_i263
#CELL
  pure_quanta q_res *
  page17_i264
#CELL
  pure_quanta q_res *
  page17_i267
#ISCELL
  logical_power vccaux15 *
  page17_i268
#ISCELL
  logical_power vccaux15 *
  page17_i269
#ISCELL
  logical_power vccaux15 *
  page17_i270
#ISCELL
  logical_power vccaux15 *
  page17_i271
#CELL
  pure_quanta q_inductor *
  page17_i272
#ISCELL
  logical_power vccaux15 *
  page17_i273
#CELL
  pure_quanta mosfet_nch_4d1s *
  page17_i274
#ISCELL
  logical_power universal_power *
  page17_i276
#CELL
  pure_quanta q_res *
  page17_i278
#CELL
  pure_quanta q_res *
  page17_i279
#ISCELL
  logical_power universal_power *
  page17_i283
#CELL
  pure_quanta q_res *
  page17_i284
#ISCELL
  logical_power universal_gnd *
  page17_i285
#CELL
  pure_quanta ast2600a3gp *
  page17_i286
#CELL
  pure_quanta mosfet_pch_gds *
  page17_i289
#ISCELL
  logical_power universal_power *
  page17_i90
#ISCELL
  logical_power universal_power *
  page17_i91
#CELL
  pure_quanta q_res *
  page17_i92
#ISCELL
  logical_power universal_power *
  page17_i93
#CELL
  pure_quanta q_res *
  page17_i94
#CELL
  pure_quanta q_res *
  page17_i95
#ISCELL
  logical_power universal_gnd *
  page17_i96
#CELL
  pure_quanta q_cap *
  page17_i97
#CELL
  pure_quanta q_cap *
  page17_i98
#ISCELL
  logical_power universal_gnd *
  page17_i99
#ISCELL
  pure_quanta quanta_title_block_c *
  *
#ISCELL
  pure_quanta quanta_title_block_c *
  *
#ISCELL
  mstr_misc dns *
  *
#ISCELL
  pure_quanta quanta_title_block_c *
  *
#ISCELL
  standard offpage *
  page20_i1
#ISCELL
  standard offpage *
  page20_i10
#ISCELL
  standard offpage *
  page20_i100
#ISCELL
  standard offpage *
  page20_i101
#ISCELL
  standard offpage *
  page20_i102
#ISCELL
  standard offpage *
  page20_i103
#ISCELL
  standard offpage *
  page20_i104
#ISCELL
  standard offpage *
  page20_i105
#CELL
  pure_quanta q_cap *
  page20_i106
#CELL
  pure_quanta q_cap *
  page20_i107
#ISCELL
  logical_power universal_gnd *
  page20_i108
#ISCELL
  logical_power universal_gnd *
  page20_i109
#ISCELL
  standard offpage *
  page20_i11
#ISCELL
  logical_power universal_power *
  page20_i110
#CELL
  pure_quanta q_res *
  page20_i111
#ISCELL
  logical_power universal_gnd *
  page20_i112
#CELL
  pure_quanta q_cap *
  page20_i113
#CELL
  pure_quanta q_res *
  page20_i114
#CELL
  pure_quanta q_res *
  page20_i115
#CELL
  pure_quanta q_res *
  page20_i116
#CELL
  pure_quanta q_res *
  page20_i117
#CELL
  pure_quanta q_res *
  page20_i118
#CELL
  pure_quanta q_res *
  page20_i119
#ISCELL
  standard offpage *
  page20_i12
#CELL
  pure_quanta q_res *
  page20_i120
#CELL
  pure_quanta q_res *
  page20_i121
#CELL
  pure_quanta q_res *
  page20_i122
#CELL
  pure_quanta q_res *
  page20_i123
#CELL
  pure_quanta q_res *
  page20_i124
#CELL
  pure_quanta q_res *
  page20_i125
#ISCELL
  logical_power universal_gnd *
  page20_i126
#CELL
  pure_quanta q_res *
  page20_i127
#CELL
  pure_quanta q_res *
  page20_i128
#CELL
  pure_quanta q_res *
  page20_i129
#CELL
  pure_quanta q_res *
  page20_i13
#CELL
  pure_quanta q_res *
  page20_i130
#CELL
  pure_quanta q_res *
  page20_i131
#CELL
  pure_quanta q_res *
  page20_i132
#ISCELL
  logical_power universal_gnd *
  page20_i133
#CELL
  pure_quanta q_cap *
  page20_i134
#CELL
  pure_quanta q_res *
  page20_i135
#CELL
  pure_quanta q_res *
  page20_i136
#CELL
  pure_quanta q_res *
  page20_i137
#CELL
  pure_quanta q_res *
  page20_i138
#ISCELL
  logical_power universal_power *
  page20_i139
#CELL
  pure_quanta q_res *
  page20_i14
#ISCELL
  logical_power universal_power *
  page20_i140
#CELL
  pure_quanta q_res *
  page20_i141
#CELL
  pure_quanta q_res *
  page20_i142
#CELL
  pure_quanta q_res *
  page20_i143
#ISCELL
  standard tap *
  page20_i144
#ISCELL
  standard tap *
  page20_i145
#ISCELL
  standard tap *
  page20_i146
#ISCELL
  standard tap *
  page20_i147
#ISCELL
  standard tap *
  page20_i148
#ISCELL
  standard tap *
  page20_i149
#ISCELL
  logical_power universal_gnd *
  page20_i15
#ISCELL
  standard tap *
  page20_i150
#ISCELL
  standard tap *
  page20_i151
#ISCELL
  standard tap *
  page20_i152
#ISCELL
  standard tap *
  page20_i153
#ISCELL
  standard tap *
  page20_i154
#ISCELL
  standard tap *
  page20_i155
#ISCELL
  standard offpage *
  page20_i156
#ISCELL
  standard tap *
  page20_i157
#ISCELL
  standard tap *
  page20_i158
#CELL
  pure_quanta q_res *
  page20_i159
#ISCELL
  logical_power universal_gnd *
  page20_i16
#CELL
  pure_quanta q_res *
  page20_i160
#CELL
  pure_quanta q_res *
  page20_i161
#CELL
  pure_quanta q_res *
  page20_i162
#CELL
  pure_quanta q_res *
  page20_i163
#CELL
  pure_quanta q_res *
  page20_i164
#CELL
  pure_quanta q_res *
  page20_i165
#CELL
  pure_quanta q_res *
  page20_i166
#CELL
  pure_quanta q_res *
  page20_i167
#CELL
  pure_quanta q_res *
  page20_i168
#CELL
  pure_quanta q_res *
  page20_i169
#CELL
  pure_quanta q_res *
  page20_i17
#CELL
  pure_quanta q_res *
  page20_i170
#CELL
  pure_quanta q_res *
  page20_i171
#CELL
  pure_quanta q_res *
  page20_i172
#CELL
  pure_quanta q_res *
  page20_i173
#CELL
  pure_quanta q_res *
  page20_i174
#CELL
  pure_quanta q_res *
  page20_i175
#CELL
  pure_quanta q_res *
  page20_i176
#CELL
  pure_quanta q_res *
  page20_i177
#CELL
  pure_quanta q_res *
  page20_i178
#CELL
  pure_quanta q_res *
  page20_i179
#ISCELL
  standard offpage *
  page20_i18
#CELL
  pure_quanta q_res *
  page20_i180
#CELL
  pure_quanta q_res *
  page20_i181
#CELL
  pure_quanta q_res *
  page20_i182
#CELL
  pure_quanta q_res *
  page20_i183
#CELL
  pure_quanta q_res *
  page20_i184
#ISCELL
  logical_power universal_gnd *
  page20_i185
#CELL
  pure_quanta q_cap *
  page20_i186
#CELL
  pure_quanta q_cap *
  page20_i187
#ISCELL
  logical_power universal_gnd *
  page20_i188
#ISCELL
  logical_power universal_gnd *
  page20_i189
#CELL
  pure_quanta q_cap *
  page20_i19
#CELL
  pure_quanta q_cap *
  page20_i190
#ISCELL
  logical_power universal_gnd *
  page20_i191
#CELL
  pure_quanta q_cap *
  page20_i192
#CELL
  pure_quanta q_res *
  page20_i193
#CELL
  pure_quanta q_res *
  page20_i194
#ISCELL
  logical_power universal_power *
  page20_i195
#CELL
  pure_quanta k4a8g165wcbctd *
  page20_i196
#CELL
  pure_quanta q_cap *
  page20_i197
#CELL
  pure_quanta q_cap *
  page20_i198
#CELL
  pure_quanta q_cap *
  page20_i199
#ISCELL
  standard offpage *
  page20_i2
#ISCELL
  logical_power universal_gnd *
  page20_i20
#ISCELL
  logical_power universal_gnd *
  page20_i200
#CELL
  pure_quanta q_cap *
  page20_i21
#ISCELL
  logical_power universal_power *
  page20_i22
#CELL
  pure_quanta q_cap *
  page20_i23
#CELL
  pure_quanta q_cap *
  page20_i24
#CELL
  pure_quanta q_cap *
  page20_i25
#CELL
  pure_quanta q_res *
  page20_i27
#CELL
  pure_quanta q_res *
  page20_i28
#ISCELL
  standard offpage *
  page20_i29
#ISCELL
  logical_power universal_gnd *
  page20_i3
#ISCELL
  standard offpage *
  page20_i30
#ISCELL
  logical_power universal_gnd *
  page20_i31
#CELL
  pure_quanta q_cap *
  page20_i32
#CELL
  pure_quanta q_cap *
  page20_i33
#CELL
  pure_quanta q_cap *
  page20_i34
#ISCELL
  logical_power universal_power *
  page20_i35
#ISCELL
  logical_power universal_gnd *
  page20_i36
#ISCELL
  standard offpage *
  page20_i37
#ISCELL
  standard offpage *
  page20_i38
#ISCELL
  logical_power universal_gnd *
  page20_i39
#CELL
  pure_quanta q_cap *
  page20_i4
#ISCELL
  standard offpage *
  page20_i40
#ISCELL
  standard tap *
  page20_i41
#ISCELL
  standard tap *
  page20_i42
#ISCELL
  standard tap *
  page20_i43
#ISCELL
  standard tap *
  page20_i44
#ISCELL
  standard tap *
  page20_i45
#ISCELL
  standard tap *
  page20_i46
#ISCELL
  standard tap *
  page20_i47
#ISCELL
  standard tap *
  page20_i48
#ISCELL
  standard offpage *
  page20_i49
#CELL
  pure_quanta q_cap *
  page20_i5
#ISCELL
  standard offpage *
  page20_i50
#ISCELL
  standard offpage *
  page20_i51
#ISCELL
  standard offpage *
  page20_i52
#ISCELL
  standard offpage *
  page20_i53
#ISCELL
  standard offpage *
  page20_i54
#ISCELL
  standard offpage *
  page20_i55
#ISCELL
  standard tap *
  page20_i56
#ISCELL
  standard tap *
  page20_i57
#ISCELL
  standard tap *
  page20_i58
#ISCELL
  standard tap *
  page20_i59
#CELL
  pure_quanta q_cap *
  page20_i6
#ISCELL
  standard tap *
  page20_i60
#ISCELL
  standard tap *
  page20_i61
#ISCELL
  standard tap *
  page20_i62
#ISCELL
  standard tap *
  page20_i63
#ISCELL
  standard tap *
  page20_i64
#ISCELL
  standard tap *
  page20_i65
#ISCELL
  standard tap *
  page20_i66
#ISCELL
  standard tap *
  page20_i67
#ISCELL
  standard tap *
  page20_i68
#ISCELL
  standard tap *
  page20_i69
#CELL
  pure_quanta q_cap *
  page20_i7
#ISCELL
  standard tap *
  page20_i70
#ISCELL
  standard tap *
  page20_i71
#ISCELL
  standard tap *
  page20_i72
#ISCELL
  standard tap *
  page20_i73
#ISCELL
  standard tap *
  page20_i74
#ISCELL
  standard tap *
  page20_i75
#ISCELL
  standard tap *
  page20_i76
#ISCELL
  standard tap *
  page20_i77
#ISCELL
  standard offpage *
  page20_i78
#ISCELL
  standard offpage *
  page20_i79
#ISCELL
  logical_power universal_power *
  page20_i8
#ISCELL
  standard offpage *
  page20_i80
#ISCELL
  standard offpage *
  page20_i81
#ISCELL
  standard offpage *
  page20_i82
#ISCELL
  standard offpage *
  page20_i83
#ISCELL
  standard offpage *
  page20_i84
#CELL
  pure_quanta q_cap *
  page20_i85
#ISCELL
  standard offpage *
  page20_i86
#ISCELL
  standard offpage *
  page20_i87
#ISCELL
  standard offpage *
  page20_i88
#CELL
  pure_quanta q_res *
  page20_i89
#ISCELL
  standard offpage *
  page20_i9
#CELL
  pure_quanta q_res *
  page20_i90
#ISCELL
  logical_power universal_power *
  page20_i91
#ISCELL
  standard offpage *
  page20_i92
#ISCELL
  logical_power universal_gnd *
  page20_i93
#ISCELL
  logical_power universal_gnd *
  page20_i94
#ISCELL
  standard offpage *
  page20_i95
#ISCELL
  standard offpage *
  page20_i96
#ISCELL
  standard offpage *
  page20_i97
#ISCELL
  standard offpage *
  page20_i98
#ISCELL
  standard offpage *
  page20_i99
#ISCELL
  mstr_misc dns *
  *
#ISCELL
  pure_quanta quanta_title_block_c *
  *
#ISCELL
  standard offpage *
  page21_i1
#CELL
  pure_quanta q_res *
  page21_i100
#CELL
  pure_quanta q_res *
  page21_i101
#ISCELL
  standard offpage *
  page21_i108
#ISCELL
  standard offpage *
  page21_i109
#ISCELL
  standard offpage *
  page21_i110
#ISCELL
  standard offpage *
  page21_i111
#ISCELL
  logical_power universal_power *
  page21_i112
#ISCELL
  standard offpage *
  page21_i113
#ISCELL
  standard offpage *
  page21_i114
#ISCELL
  standard offpage *
  page21_i115
#ISCELL
  standard offpage *
  page21_i116
#ISCELL
  standard offpage *
  page21_i117
#ISCELL
  standard offpage *
  page21_i118
#ISCELL
  standard offpage *
  page21_i119
#ISCELL
  standard offpage *
  page21_i120
#ISCELL
  standard offpage *
  page21_i121
#ISCELL
  standard offpage *
  page21_i122
#ISCELL
  standard offpage *
  page21_i123
#ISCELL
  logical_power universal_gnd *
  page21_i124
#CELL
  pure_quanta q_res *
  page21_i125
#ISCELL
  standard offpage *
  page21_i126
#ISCELL
  standard offpage *
  page21_i127
#CELL
  pure_quanta q_res *
  page21_i128
#ISCELL
  standard offpage *
  page21_i133
#ISCELL
  standard offpage *
  page21_i134
#ISCELL
  standard offpage *
  page21_i135
#ISCELL
  standard offpage *
  page21_i136
#ISCELL
  standard offpage *
  page21_i138
#ISCELL
  logical_power universal_power *
  page21_i139
#ISCELL
  standard offpage *
  page21_i14
#ISCELL
  logical_power universal_gnd *
  page21_i145
#ISCELL
  logical_power universal_gnd *
  page21_i146
#CELL
  pure_quanta q_res *
  page21_i147
#ISCELL
  logical_power universal_power *
  page21_i148
#ISCELL
  standard offpage *
  page21_i149
#ISCELL
  standard offpage *
  page21_i152
#ISCELL
  standard offpage *
  page21_i154
#ISCELL
  standard offpage *
  page21_i155
#CELL
  pure_quanta q_res *
  page21_i156
#CELL
  pure_quanta q_res *
  page21_i157
#ISCELL
  logical_power universal_power *
  page21_i160
#CELL
  pure_quanta q_res *
  page21_i161
#ISCELL
  standard offpage *
  page21_i162
#CELL
  pure_quanta q_res *
  page21_i166
#CELL
  pure_quanta q_res *
  page21_i167
#CELL
  pure_quanta q_res *
  page21_i168
#ISCELL
  logical_power universal_power *
  page21_i169
#ISCELL
  logical_power universal_power *
  page21_i171
#CELL
  pure_quanta q_res *
  page21_i172
#CELL
  pure_quanta q_res *
  page21_i173
#CELL
  pure_quanta q_res *
  page21_i174
#CELL
  pure_quanta q_res *
  page21_i175
#CELL
  pure_quanta q_res *
  page21_i176
#CELL
  pure_quanta q_res *
  page21_i177
#CELL
  pure_quanta q_res *
  page21_i178
#CELL
  pure_quanta q_res *
  page21_i179
#CELL
  pure_quanta q_res *
  page21_i180
#CELL
  pure_quanta q_res *
  page21_i181
#CELL
  pure_quanta q_res *
  page21_i182
#ISCELL
  logical_power universal_gnd *
  page21_i20
#CELL
  pure_quanta q_cap *
  page21_i21
#ISCELL
  standard offpage *
  page21_i25
#ISCELL
  logical_power universal_power *
  page21_i3
#CELL
  pure_quanta q_res *
  page21_i33
#CELL
  pure_quanta q_res *
  page21_i35
#CELL
  pure_quanta q_res *
  page21_i42
#CELL
  pure_quanta q_res *
  page21_i43
#CELL
  pure_quanta q_res *
  page21_i45
#CELL
  pure_quanta q_res *
  page21_i46
#ISCELL
  logical_power universal_power *
  page21_i47
#CELL
  pure_quanta q_res *
  page21_i58
#CELL
  pure_quanta q_res *
  page21_i59
#CELL
  pure_quanta q_res *
  page21_i60
#CELL
  pure_quanta q_res *
  page21_i61
#CELL
  pure_quanta q_res *
  page21_i62
#CELL
  pure_quanta q_res *
  page21_i63
#CELL
  pure_quanta q_res *
  page21_i64
#CELL
  pure_quanta q_res *
  page21_i66
#CELL
  pure_quanta q_res *
  page21_i67
#ISCELL
  standard offpage *
  page21_i70
#ISCELL
  standard offpage *
  page21_i71
#ISCELL
  standard offpage *
  page21_i72
#ISCELL
  standard offpage *
  page21_i73
#ISCELL
  standard offpage *
  page21_i74
#ISCELL
  standard offpage *
  page21_i75
#ISCELL
  standard offpage *
  page21_i76
#ISCELL
  standard offpage *
  page21_i77
#ISCELL
  standard offpage *
  page21_i78
#CELL
  pure_quanta q_cap *
  page21_i80
#CELL
  pure_quanta q_cap *
  page21_i81
#CELL
  pure_quanta sconn67_nasa0s6730ts67 *
  page21_i84
#ISCELL
  standard offpage *
  page21_i85
#ISCELL
  standard offpage *
  page21_i86
#ISCELL
  standard offpage *
  page21_i87
#ISCELL
  standard offpage *
  page21_i89
#CELL
  pure_quanta q_res *
  page21_i98
#CELL
  pure_quanta q_res *
  page21_i99
#ISCELL
  mstr_misc dns *
  *
#ISCELL
  pure_quanta quanta_title_block_c *
  *
#CELL
  pure_quanta q_res *
  page22_i10
#CELL
  pure_quanta q_res *
  page22_i100
#CELL
  pure_quanta q_res *
  page22_i101
#CELL
  pure_quanta q_res *
  page22_i102
#ISCELL
  logical_power universal_power *
  page22_i103
#ISCELL
  logical_power universal_power *
  page22_i104
#CELL
  pure_quanta q_res *
  page22_i106
#CELL
  pure_quanta q_cap *
  page22_i107
#ISCELL
  standard offpage *
  page22_i11
#CELL
  pure_quanta q_res *
  page22_i12
#ISCELL
  standard offpage *
  page22_i13
#CELL
  pure_quanta mosfet_n *
  page22_i14
#ISCELL
  logical_power universal_power *
  page22_i16
#CELL
  pure_quanta q_cap *
  page22_i17
#ISCELL
  logical_power universal_gnd *
  page22_i18
#CELL
  pure_quanta mmbt39047f *
  page22_i2
#ISCELL
  logical_power universal_gnd *
  page22_i22
#CELL
  pure_quanta q_cap *
  page22_i23
#ISCELL
  logical_power universal_gnd *
  page22_i25
#CELL
  pure_quanta q_res *
  page22_i26
#ISCELL
  logical_power universal_gnd *
  page22_i27
#CELL
  pure_quanta q_diode *
  page22_i28
#ISCELL
  standard offpage *
  page22_i29
#ISCELL
  logical_power universal_gnd *
  page22_i3
#CELL
  pure_quanta q_res *
  page22_i30
#ISCELL
  logical_power universal_gnd *
  page22_i31
#ISCELL
  standard offpage *
  page22_i32
#ISCELL
  logical_power universal_gnd *
  page22_i34
#CELL
  pure_quanta q_res *
  page22_i35
#ISCELL
  logical_power universal_gnd *
  page22_i36
#CELL
  pure_quanta mmbt39047f *
  page22_i4
#CELL
  pure_quanta q_res *
  page22_i41
#CELL
  pure_quanta q_cap *
  page22_i42
#ISCELL
  logical_power universal_gnd *
  page22_i43
#ISCELL
  logical_power universal_power *
  page22_i44
#ISCELL
  logical_power universal_gnd *
  page22_i45
#CELL
  pure_quanta q_cap *
  page22_i46
#ISCELL
  logical_power universal_gnd *
  page22_i48
#CELL
  pure_quanta q_res *
  page22_i49
#CELL
  pure_quanta q_res *
  page22_i5
#ISCELL
  standard offpage *
  page22_i50
#ISCELL
  standard offpage *
  page22_i52
#ISCELL
  logical_power vccaux15 *
  page22_i53
#ISCELL
  logical_power universal_power *
  page22_i54
#CELL
  pure_quanta q_res *
  page22_i55
#ISCELL
  logical_power universal_power *
  page22_i56
#CELL
  pure_quanta q_cap *
  page22_i57
#ISCELL
  logical_power universal_gnd *
  page22_i58
#CELL
  pure_quanta q_cap *
  page22_i59
#ISCELL
  logical_power universal_gnd *
  page22_i6
#ISCELL
  logical_power universal_gnd *
  page22_i61
#CELL
  pure_quanta q_res *
  page22_i65
#ISCELL
  logical_power universal_power *
  page22_i66
#CELL
  pure_quanta q_res *
  page22_i67
#ISCELL
  standard offpage *
  page22_i68
#CELL
  pure_quanta q_res *
  page22_i69
#CELL
  pure_quanta q_res *
  page22_i7
#CELL
  pure_quanta q_res *
  page22_i71
#CELL
  pure_quanta q_res *
  page22_i72
#ISCELL
  standard offpage *
  page22_i73
#CELL
  pure_quanta q_res *
  page22_i74
#ISCELL
  standard offpage *
  page22_i76
#ISCELL
  standard offpage *
  page22_i79
#CELL
  pure_quanta q_res *
  page22_i8
#ISCELL
  logical_power universal_power *
  page22_i80
#CELL
  pure_quanta q_res *
  page22_i81
#ISCELL
  logical_power universal_power *
  page22_i82
#CELL
  pure_quanta q_res *
  page22_i83
#ISCELL
  logical_power universal_power *
  page22_i84
#ISCELL
  logical_power universal_power *
  page22_i85
#CELL
  pure_quanta 74lvc2g07dw7 *
  page22_i87
#CELL
  pure_quanta mc74vhc1g07dft2g *
  page22_i89
#CELL
  pure_quanta q_res *
  page22_i9
#CELL
  pure_quanta tps3808g18dbvr *
  page22_i90
#ISCELL
  standard offpage *
  page22_i91
#CELL
  pure_quanta q_res *
  page22_i92
#CELL
  pure_quanta mc74vhc1g32dtt1g *
  page22_i94
#ISCELL
  logical_power universal_gnd *
  page22_i95
#ISCELL
  logical_power universal_gnd *
  page22_i96
#CELL
  pure_quanta q_cap *
  page22_i97
#ISCELL
  logical_power vccaux15 *
  page22_i98
#ISCELL
  mstr_misc dns *
  *
#ISCELL
  pure_quanta quanta_title_block_c *
  *
#ISCELL
  standard offpage *
  page23_i1
#ISCELL
  logical_power universal_gnd *
  page23_i10
#CELL
  pure_quanta q_cap *
  page23_i11
#CELL
  pure_quanta q_cap *
  page23_i12
#ISCELL
  logical_power universal_power *
  page23_i13
#ISCELL
  standard offpage *
  page23_i14
#ISCELL
  standard offpage *
  page23_i143
#ISCELL
  standard offpage *
  page23_i144
#ISCELL
  standard offpage *
  page23_i145
#ISCELL
  standard offpage *
  page23_i146
#ISCELL
  standard offpage *
  page23_i147
#ISCELL
  standard offpage *
  page23_i148
#ISCELL
  standard offpage *
  page23_i149
#ISCELL
  standard offpage *
  page23_i15
#ISCELL
  logical_power universal_gnd *
  page23_i150
#CELL
  pure_quanta q_fuse *
  page23_i153
#ISCELL
  logical_power universal_power *
  page23_i154
#CELL
  pure_quanta dt1240e04lp7 *
  page23_i155
#CELL
  pure_quanta dt1240e04lp7 *
  page23_i156
#ISCELL
  logical_power universal_gnd *
  page23_i157
#ISCELL
  logical_power universal_gnd *
  page23_i158
#ISCELL
  standard offpage *
  page23_i16
#CELL
  pure_quanta schottky_12 *
  page23_i161
#CELL
  pure_quanta sconn13_502280130cv01 *
  page23_i165
#CELL
  pure_quanta q_inductor *
  page23_i166
#CELL
  pure_quanta q_inductor *
  page23_i167
#CELL
  pure_quanta q_inductor *
  page23_i168
#CELL
  pure_quanta q_cap *
  page23_i169
#ISCELL
  standard offpage *
  page23_i17
#CELL
  pure_quanta q_cap *
  page23_i170
#ISCELL
  standard offpage *
  page23_i18
#CELL
  pure_quanta q_res *
  page23_i19
#CELL
  pure_quanta mosfet_nch_dual *
  page23_i2
#ISCELL
  standard offpage *
  page23_i20
#ISCELL
  standard offpage *
  page23_i21
#ISCELL
  logical_power universal_power *
  page23_i22
#ISCELL
  standard offpage *
  page23_i23
#ISCELL
  logical_power universal_gnd *
  page23_i24
#CELL
  pure_quanta q_cap *
  page23_i25
#CELL
  pure_quanta q_cap *
  page23_i26
#CELL
  pure_quanta q_res *
  page23_i27
#ISCELL
  logical_power universal_power *
  page23_i28
#CELL
  pure_quanta q_cap *
  page23_i29
#ISCELL
  standard offpage *
  page23_i3
#ISCELL
  logical_power universal_gnd *
  page23_i31
#CELL
  pure_quanta 74hc1g126gw *
  page23_i32
#CELL
  pure_quanta 74hc1g126gw *
  page23_i33
#CELL
  pure_quanta q_res *
  page23_i34
#CELL
  pure_quanta q_res *
  page23_i39
#CELL
  pure_quanta q_res *
  page23_i40
#CELL
  pure_quanta schottky_ac *
  page23_i41
#CELL
  pure_quanta schottky_ac *
  page23_i42
#ISCELL
  logical_power universal_gnd *
  page23_i44
#CELL
  pure_quanta q_cap *
  page23_i45
#ISCELL
  logical_power universal_power *
  page23_i46
#ISCELL
  logical_power universal_power *
  page23_i47
#CELL
  pure_quanta q_res *
  page23_i50
#CELL
  pure_quanta q_res *
  page23_i51
#ISCELL
  logical_power universal_power *
  page23_i52
#ISCELL
  logical_power universal_gnd *
  page23_i53
#CELL
  pure_quanta q_cap *
  page23_i54
#CELL
  pure_quanta mosfet_nch_dual *
  page23_i56
#CELL
  pure_quanta q_res *
  page23_i57
#ISCELL
  logical_power universal_gnd *
  page23_i58
#CELL
  pure_quanta q_res *
  page23_i59
#CELL
  pure_quanta q_res *
  page23_i60
#CELL
  pure_quanta q_res *
  page23_i61
#CELL
  pure_quanta q_res *
  page23_i62
#ISCELL
  logical_power universal_power *
  page23_i63
#CELL
  pure_quanta q_res *
  page23_i64
#CELL
  pure_quanta q_res *
  page23_i65
#ISCELL
  standard offpage *
  page23_i66
#CELL
  pure_quanta q_cap *
  page23_i67
#CELL
  pure_quanta q_res *
  page23_i68
#ISCELL
  logical_power universal_power *
  page23_i71
#ISCELL
  logical_power universal_gnd *
  page23_i73
#CELL
  pure_quanta bza462a *
  page23_i74
#CELL
  pure_quanta q_res *
  page23_i75
#ISCELL
  logical_power universal_gnd *
  page23_i76
#CELL
  pure_quanta q_cap *
  page23_i77
#ISCELL
  logical_power universal_gnd *
  page23_i82
#CELL
  pure_quanta q_cap *
  page23_i83
#CELL
  pure_quanta q_cap *
  page23_i84
#ISCELL
  standard offpage *
  page23_i88
#ISCELL
  standard offpage *
  page23_i89
#ISCELL
  standard offpage *
  page23_i90
#ISCELL
  standard offpage *
  page23_i91
#ISCELL
  standard offpage *
  page23_i92
#ISCELL
  standard offpage *
  page23_i93
#ISCELL
  standard offpage *
  page23_i94
#ISCELL
  logical_power universal_power *
  page23_i97
#ISCELL
  logical_power universal_power *
  page23_i98
#CELL
  pure_quanta q_res *
  page23_i99
#ISCELL
  pure_quanta quanta_title_block_c *
  *
#ISCELL
  mstr_misc dns *
  *
#ISCELL
  pure_quanta quanta_title_block_c *
  *
#ISCELL
  logical_power universal_power *
  page25_i135
#ISCELL
  standard offpage *
  page25_i137
#CELL
  pure_quanta 74lvc1g74dp *
  page25_i138
#ISCELL
  standard offpage *
  page25_i139
#ISCELL
  standard offpage *
  page25_i140
#CELL
  pure_quanta q_res *
  page25_i142
#CELL
  pure_quanta q_res *
  page25_i143
#ISCELL
  logical_power universal_gnd *
  page25_i144
#ISCELL
  logical_power universal_power *
  page25_i145
#CELL
  pure_quanta q_cap *
  page25_i146
#ISCELL
  logical_power universal_gnd *
  page25_i147
#CELL
  pure_quanta q_res *
  page25_i149
#CELL
  pure_quanta sn74lvc1g14dckr *
  page25_i150
#ISCELL
  standard offpage *
  page25_i152
#ISCELL
  logical_power universal_power *
  page25_i153
#CELL
  pure_quanta q_cap *
  page25_i154
#ISCELL
  logical_power universal_gnd *
  page25_i155
#CELL
  pure_quanta q_res *
  page25_i156
#ISCELL
  logical_power universal_gnd *
  page25_i157
#ISCELL
  logical_power universal_gnd *
  page25_i158
#ISCELL
  standard offpage *
  page25_i162
#ISCELL
  standard offpage *
  page25_i163
#ISCELL
  logical_power universal_power *
  page25_i166
#CELL
  pure_quanta sconn3_212h9103gbr1 *
  page25_i169
#CELL
  pure_quanta q_res *
  page25_i170
#CELL
  pure_quanta q_res *
  page25_i171
#CELL
  pure_quanta q_res *
  page25_i172
#CELL
  pure_quanta q_res *
  page25_i173
#CELL
  pure_quanta q_res *
  page25_i174
#CELL
  pure_quanta q_res *
  page25_i175
#CELL
  pure_quanta q_res *
  page25_i176
#ISCELL
  logical_power universal_power *
  page25_i2
#CELL
  pure_quanta q_res *
  page25_i3
#CELL
  pure_quanta sn74lvc1g07dckr *
  page25_i61
#ISCELL
  logical_power universal_gnd *
  page25_i62
#ISCELL
  logical_power universal_gnd *
  page25_i64
#CELL
  pure_quanta q_cap *
  page25_i65
#CELL
  pure_quanta q_res *
  page25_i67
#ISCELL
  standard offpage *
  page25_i70
#ISCELL
  standard offpage *
  page25_i71
#ISCELL
  logical_power universal_power *
  page25_i72
#CELL
  pure_quanta q_res *
  page25_i73
#ISCELL
  mstr_misc dns *
  *
#ISCELL
  pure_quanta quanta_title_block_c *
  *
#ISCELL
  logical_power universal_power *
  page26_i10
#CELL
  pure_quanta q_res *
  page26_i11
#CELL
  pure_quanta q_res *
  page26_i12
#ISCELL
  logical_power universal_gnd *
  page26_i13
#CELL
  pure_quanta q_res *
  page26_i14
#CELL
  pure_quanta m24128bwdw6tp *
  page26_i15
#ISCELL
  logical_power universal_gnd *
  page26_i16
#CELL
  pure_quanta q_cap *
  page26_i17
#ISCELL
  logical_power universal_power *
  page26_i18
#ISCELL
  logical_power universal_gnd *
  page26_i31
#CELL
  pure_quanta q_res *
  page26_i32
#CELL
  pure_quanta q_res *
  page26_i33
#ISCELL
  standard offpage *
  page26_i35
#ISCELL
  standard offpage *
  page26_i36
#CELL
  pure_quanta q_res *
  page26_i37
#ISCELL
  logical_power universal_gnd *
  page26_i38
#CELL
  pure_quanta q_res *
  page26_i39
#CELL
  pure_quanta q_res *
  page26_i40
#CELL
  pure_quanta q_res *
  page26_i41
#ISCELL
  logical_power universal_gnd *
  page26_i52
#ISCELL
  logical_power universal_power *
  page26_i53
#CELL
  pure_quanta q_cap *
  page26_i54
#ISCELL
  logical_power universal_gnd *
  page26_i55
#CELL
  pure_quanta q_res *
  page26_i56
#CELL
  pure_quanta q_res *
  page26_i57
#ISCELL
  logical_power universal_power *
  page26_i58
#ISCELL
  standard offpage *
  page26_i59
#CELL
  pure_quanta q_res *
  page26_i6
#ISCELL
  standard offpage *
  page26_i60
#CELL
  pure_quanta q_res *
  page26_i65
#CELL
  pure_quanta q_res *
  page26_i66
#CELL
  pure_quanta q_res *
  page26_i67
#ISCELL
  standard offpage *
  page26_i68
#CELL
  pure_quanta q_res *
  page26_i69
#ISCELL
  logical_power universal_gnd *
  page26_i7
#CELL
  pure_quanta conn8_tsw10407fd *
  page26_i71
#CELL
  pure_quanta q_res *
  page26_i8
#CELL
  pure_quanta q_res *
  page26_i9
#ISCELL
  logical_power design_note *
  *
#ISCELL
  mstr_misc dns *
  *
#ISCELL
  pure_quanta quanta_title_block_c *
  *
#CELL
  pure_quanta q_res *
  page27_i100
#CELL
  pure_quanta q_res *
  page27_i101
#CELL
  pure_quanta q_res *
  page27_i102
#CELL
  pure_quanta q_res *
  page27_i103
#CELL
  pure_quanta q_res *
  page27_i105
#CELL
  pure_quanta q_res *
  page27_i106
#CELL
  pure_quanta q_res *
  page27_i107
#CELL
  pure_quanta q_res *
  page27_i108
#CELL
  pure_quanta q_res *
  page27_i109
#ISCELL
  logical_power universal_power *
  page27_i110
#ISCELL
  standard offpage *
  page27_i119
#ISCELL
  standard offpage *
  page27_i120
#ISCELL
  standard offpage *
  page27_i121
#ISCELL
  standard offpage *
  page27_i122
#ISCELL
  standard offpage *
  page27_i123
#ISCELL
  standard offpage *
  page27_i124
#ISCELL
  standard offpage *
  page27_i125
#ISCELL
  standard offpage *
  page27_i126
#ISCELL
  standard offpage *
  page27_i127
#ISCELL
  standard offpage *
  page27_i128
#ISCELL
  standard offpage *
  page27_i129
#ISCELL
  standard offpage *
  page27_i130
#ISCELL
  standard offpage *
  page27_i131
#ISCELL
  standard offpage *
  page27_i132
#ISCELL
  standard offpage *
  page27_i133
#ISCELL
  standard offpage *
  page27_i134
#ISCELL
  standard offpage *
  page27_i135
#ISCELL
  standard offpage *
  page27_i136
#ISCELL
  standard offpage *
  page27_i137
#ISCELL
  standard offpage *
  page27_i138
#ISCELL
  standard offpage *
  page27_i139
#ISCELL
  standard offpage *
  page27_i14
#ISCELL
  standard offpage *
  page27_i140
#ISCELL
  standard offpage *
  page27_i141
#ISCELL
  standard offpage *
  page27_i142
#ISCELL
  standard offpage *
  page27_i143
#ISCELL
  standard offpage *
  page27_i144
#CELL
  pure_quanta q_res *
  page27_i145
#CELL
  pure_quanta q_res *
  page27_i146
#CELL
  pure_quanta q_res *
  page27_i147
#ISCELL
  standard offpage *
  page27_i148
#ISCELL
  standard offpage *
  page27_i155
#ISCELL
  standard offpage *
  page27_i156
#ISCELL
  standard offpage *
  page27_i158
#ISCELL
  logical_power vccaux15 *
  page27_i160
#ISCELL
  standard offpage *
  page27_i161
#ISCELL
  standard offpage *
  page27_i162
#CELL
  pure_quanta q_res *
  page27_i163
#ISCELL
  logical_power vccaux15 *
  page27_i164
#CELL
  pure_quanta q_res *
  page27_i165
#CELL
  pure_quanta q_cap *
  page27_i166
#ISCELL
  logical_power universal_gnd *
  page27_i167
#CELL
  pure_quanta q_res *
  page27_i168
#ISCELL
  standard offpage *
  page27_i169
#ISCELL
  standard offpage *
  page27_i170
#ISCELL
  standard offpage *
  page27_i173
#ISCELL
  standard offpage *
  page27_i174
#ISCELL
  standard offpage *
  page27_i175
#CELL
  pure_quanta q_res *
  page27_i177
#CELL
  pure_quanta q_res *
  page27_i179
#CELL
  pure_quanta q_res *
  page27_i181
#CELL
  pure_quanta q_res *
  page27_i182
#ISCELL
  standard offpage *
  page27_i183
#CELL
  pure_quanta q_res *
  page27_i184
#CELL
  pure_quanta bat54c *
  page27_i185
#ISCELL
  standard offpage *
  page27_i186
#ISCELL
  standard offpage *
  page27_i187
#CELL
  pure_quanta q_res *
  page27_i188
#ISCELL
  logical_power universal_power *
  page27_i189
#ISCELL
  standard offpage *
  page27_i202
#ISCELL
  logical_power universal_power *
  page27_i204
#ISCELL
  standard offpage *
  page27_i205
#ISCELL
  standard offpage *
  page27_i206
#ISCELL
  standard offpage *
  page27_i207
#ISCELL
  standard offpage *
  page27_i211
#CELL
  pure_quanta q_res *
  page27_i213
#ISCELL
  logical_power universal_power *
  page27_i214
#CELL
  pure_quanta q_res *
  page27_i217
#ISCELL
  logical_power universal_gnd *
  page27_i218
#CELL
  pure_quanta q_res *
  page27_i222
#ISCELL
  logical_power universal_gnd *
  page27_i223
#CELL
  pure_quanta q_res *
  page27_i228
#ISCELL
  standard offpage *
  page27_i229
#ISCELL
  standard offpage *
  page27_i230
#ISCELL
  logical_power vccaux15 *
  page27_i231
#ISCELL
  logical_power vccaux15 *
  page27_i232
#CELL
  pure_quanta q_res *
  page27_i233
#CELL
  pure_quanta q_res *
  page27_i234
#CELL
  pure_quanta q_res *
  page27_i235
#CELL
  pure_quanta q_res *
  page27_i236
#CELL
  pure_quanta q_res *
  page27_i237
#CELL
  pure_quanta q_res *
  page27_i238
#CELL
  pure_quanta q_res *
  page27_i239
#CELL
  pure_quanta q_res *
  page27_i240
#CELL
  pure_quanta q_res *
  page27_i241
#CELL
  pure_quanta q_res *
  page27_i242
#CELL
  pure_quanta 2n7002a7 *
  page27_i243
#CELL
  pure_quanta q_res *
  page27_i244
#ISCELL
  logical_power universal_gnd *
  page27_i245
#CELL
  pure_quanta q_res *
  page27_i246
#CELL
  pure_quanta q_res *
  page27_i247
#ISCELL
  standard offpage *
  page27_i75
#CELL
  pure_quanta q_res *
  page27_i84
#CELL
  pure_quanta q_res *
  page27_i85
#CELL
  pure_quanta q_res *
  page27_i86
#ISCELL
  logical_power universal_power *
  page27_i87
#CELL
  pure_quanta q_res *
  page27_i88
#CELL
  pure_quanta q_res *
  page27_i89
#CELL
  pure_quanta q_res *
  page27_i93
#CELL
  pure_quanta q_res *
  page27_i94
#CELL
  pure_quanta q_res *
  page27_i95
#CELL
  pure_quanta q_res *
  page27_i96
#CELL
  pure_quanta q_res *
  page27_i97
#CELL
  pure_quanta q_res *
  page27_i98
#CELL
  pure_quanta q_res *
  page27_i99
#ISCELL
  mstr_misc dns *
  *
#ISCELL
  pure_quanta quanta_title_block_c *
  *
#ISCELL
  logical_power universal_gnd *
  page28_i100
#CELL
  pure_quanta q_cap *
  page28_i101
#ISCELL
  logical_power universal_gnd *
  page28_i102
#ISCELL
  standard offpage *
  page28_i103
#CELL
  pure_quanta q_res *
  page28_i104
#CELL
  pure_quanta q_res *
  page28_i105
#ISCELL
  logical_power universal_gnd *
  page28_i106
#ISCELL
  logical_power universal_power *
  page28_i107
#CELL
  pure_quanta q_res *
  page28_i108
#CELL
  pure_quanta q_res *
  page28_i109
#ISCELL
  logical_power vccaux15 *
  page28_i110
#CELL
  pure_quanta q_res *
  page28_i113
#ISCELL
  logical_power universal_gnd *
  page28_i115
#ISCELL
  standard offpage *
  page28_i116
#ISCELL
  standard offpage *
  page28_i117
#ISCELL
  standard offpage *
  page28_i118
#ISCELL
  standard offpage *
  page28_i121
#ISCELL
  standard offpage *
  page28_i122
#ISCELL
  standard offpage *
  page28_i123
#ISCELL
  standard offpage *
  page28_i124
#CELL
  pure_quanta q_res *
  page28_i125
#CELL
  pure_quanta q_res *
  page28_i126
#CELL
  pure_quanta q_res *
  page28_i127
#CELL
  pure_quanta q_res *
  page28_i128
#ISCELL
  standard offpage *
  page28_i129
#ISCELL
  standard offpage *
  page28_i130
#ISCELL
  standard offpage *
  page28_i131
#ISCELL
  standard offpage *
  page28_i132
#ISCELL
  standard offpage *
  page28_i133
#ISCELL
  standard offpage *
  page28_i134
#ISCELL
  standard offpage *
  page28_i135
#ISCELL
  standard offpage *
  page28_i136
#ISCELL
  standard offpage *
  page28_i137
#ISCELL
  standard offpage *
  page28_i138
#ISCELL
  standard offpage *
  page28_i139
#ISCELL
  logical_power universal_gnd *
  page28_i140
#CELL
  pure_quanta pca9555pw *
  page28_i141
#ISCELL
  standard offpage *
  page28_i142
#ISCELL
  standard offpage *
  page28_i143
#CELL
  pure_quanta q_res *
  page28_i144
#CELL
  pure_quanta q_res *
  page28_i145
#CELL
  pure_quanta q_cap *
  page28_i146
#CELL
  pure_quanta q_res *
  page28_i147
#ISCELL
  logical_power universal_gnd *
  page28_i148
#ISCELL
  standard offpage *
  page28_i149
#ISCELL
  standard offpage *
  page28_i150
#ISCELL
  standard offpage *
  page28_i151
#CELL
  pure_quanta q_res *
  page28_i152
#CELL
  pure_quanta q_res *
  page28_i153
#ISCELL
  logical_power universal_power *
  page28_i154
#ISCELL
  logical_power universal_power *
  page28_i155
#ISCELL
  standard offpage *
  page28_i156
#ISCELL
  standard offpage *
  page28_i157
#ISCELL
  standard offpage *
  page28_i158
#ISCELL
  logical_power universal_gnd *
  page28_i159
#ISCELL
  logical_power universal_power *
  page28_i160
#CELL
  pure_quanta q_res *
  page28_i161
#CELL
  pure_quanta q_res *
  page28_i162
#CELL
  pure_quanta 2n7002a7 *
  page28_i163
#CELL
  pure_quanta q_res *
  page28_i164
#ISCELL
  logical_power universal_power *
  page28_i165
#CELL
  pure_quanta q_res *
  page28_i166
#ISCELL
  standard offpage *
  page28_i167
#CELL
  pure_quanta q_res *
  page28_i168
#CELL
  pure_quanta q_res *
  page28_i169
#ISCELL
  logical_power universal_power *
  page28_i170
#CELL
  pure_quanta q_res *
  page28_i171
#CELL
  pure_quanta q_res *
  page28_i172
#CELL
  pure_quanta q_res *
  page28_i173
#ISCELL
  logical_power universal_gnd *
  page28_i174
#CELL
  pure_quanta q_res *
  page28_i175
#ISCELL
  standard offpage *
  page28_i176
#ISCELL
  standard offpage *
  page28_i177
#ISCELL
  standard offpage *
  page28_i178
#CELL
  pure_quanta ncp380hsnajaat1g *
  page28_i179
#CELL
  pure_quanta 74lvc1g07w57 *
  page28_i180
#CELL
  pure_quanta q_cap *
  page28_i181
#ISCELL
  logical_power universal_gnd *
  page28_i182
#CELL
  pure_quanta q_res *
  page28_i183
#CELL
  pure_quanta q_res *
  page28_i184
#CELL
  pure_quanta q_res *
  page28_i185
#CELL
  pure_quanta q_cap *
  page28_i35
#ISCELL
  logical_power universal_gnd *
  page28_i36
#ISCELL
  logical_power universal_power *
  page28_i37
#CELL
  pure_quanta q_cap *
  page28_i38
#ISCELL
  standard offpage *
  page28_i39
#ISCELL
  logical_power universal_power *
  page28_i40
#CELL
  pure_quanta q_res *
  page28_i42
#ISCELL
  logical_power universal_power *
  page28_i50
#ISCELL
  logical_power universal_power *
  page28_i52
#ISCELL
  logical_power universal_gnd *
  page28_i53
#CELL
  pure_quanta q_res *
  page28_i54
#ISCELL
  logical_power universal_power *
  page28_i61
#CELL
  pure_quanta q_res *
  page28_i62
#CELL
  pure_quanta q_res *
  page28_i63
#ISCELL
  logical_power universal_gnd *
  page28_i64
#ISCELL
  logical_power vccaux15 *
  page28_i87
#ISCELL
  logical_power vccaux15 *
  page28_i88
#ISCELL
  standard offpage *
  page28_i89
#ISCELL
  standard offpage *
  page28_i90
#CELL
  pure_quanta q_res *
  page28_i91
#ISCELL
  standard offpage *
  page28_i94
#ISCELL
  logical_power vccaux15 *
  page28_i95
#CELL
  pure_quanta q_res *
  page28_i96
#ISCELL
  logical_power universal_gnd *
  page28_i97
#CELL
  pure_quanta q_cap *
  page28_i98
#CELL
  pure_quanta pca9517adp *
  page28_i99
#ISCELL
  mstr_misc dns *
  *
#ISCELL
  pure_quanta quanta_title_block_c *
  *
#ISCELL
  logical_power universal_gnd *
  page29_i100
#CELL
  pure_quanta q_res *
  page29_i101
#CELL
  pure_quanta q_inductor4p_12 *
  page29_i102
#ISCELL
  standard offpage *
  page29_i103
#ISCELL
  standard offpage *
  page29_i104
#ISCELL
  standard offpage *
  page29_i105
#ISCELL
  standard offpage *
  page29_i106
#CELL
  pure_quanta q_res *
  page29_i109
#CELL
  pure_quanta q_res *
  page29_i111
#CELL
  pure_quanta q_inductor4p_12 *
  page29_i113
#ISCELL
  standard offpage *
  page29_i114
#ISCELL
  standard offpage *
  page29_i115
#ISCELL
  standard offpage *
  page29_i116
#ISCELL
  standard offpage *
  page29_i119
#CELL
  pure_quanta q_res *
  page29_i122
#CELL
  pure_quanta q_inductor4p_12 *
  page29_i123
#CELL
  pure_quanta q_res *
  page29_i124
#ISCELL
  standard offpage *
  page29_i125
#ISCELL
  standard offpage *
  page29_i126
#ISCELL
  standard offpage *
  page29_i127
#ISCELL
  standard offpage *
  page29_i128
#ISCELL
  standard offpage *
  page29_i133
#ISCELL
  standard offpage *
  page29_i134
#CELL
  pure_quanta q_res *
  page29_i135
#CELL
  pure_quanta q_res *
  page29_i136
#ISCELL
  standard offpage *
  page29_i137
#ISCELL
  standard offpage *
  page29_i138
#CELL
  pure_quanta q_res *
  page29_i141
#CELL
  pure_quanta q_cap *
  page29_i142
#CELL
  pure_quanta q_cap *
  page29_i143
#CELL
  pure_quanta q_res *
  page29_i144
#ISCELL
  logical_power vccaux15 *
  page29_i145
#CELL
  pure_quanta q_cap *
  page29_i146
#ISCELL
  logical_power universal_gnd *
  page29_i147
#CELL
  pure_quanta q_cap *
  page29_i148
#ISCELL
  logical_power vccaux15 *
  page29_i149
#CELL
  pure_quanta q_cap *
  page29_i150
#ISCELL
  logical_power universal_gnd *
  page29_i151
#CELL
  pure_quanta q_res *
  page29_i153
#ISCELL
  standard offpage *
  page29_i154
#CELL
  pure_quanta q_res *
  page29_i155
#ISCELL
  logical_power universal_gnd *
  page29_i156
#CELL
  pure_quanta q_res *
  page29_i157
#ISCELL
  standard offpage *
  page29_i158
#ISCELL
  logical_power vccaux15 *
  page29_i159
#ISCELL
  standard offpage *
  page29_i160
#CELL
  pure_quanta q_cap *
  page29_i161
#ISCELL
  logical_power vccaux15 *
  page29_i162
#ISCELL
  logical_power universal_gnd *
  page29_i163
#CELL
  pure_quanta 74hc1g126gw *
  page29_i164
#ISCELL
  logical_power vccaux15 *
  page29_i165
#CELL
  pure_quanta q_res *
  page29_i166
#ISCELL
  logical_power universal_gnd *
  page29_i167
#ISCELL
  standard offpage *
  page29_i168
#ISCELL
  standard offpage *
  page29_i169
#CELL
  pure_quanta q_res *
  page29_i170
#ISCELL
  logical_power universal_gnd *
  page29_i171
#CELL
  pure_quanta q_cap *
  page29_i172
#ISCELL
  logical_power universal_gnd *
  page29_i173
#CELL
  pure_quanta 74hc1g126gw *
  page29_i174
#ISCELL
  logical_power universal_gnd *
  page29_i175
#ISCELL
  standard offpage *
  page29_i176
#ISCELL
  logical_power vccaux15 *
  page29_i177
#ISCELL
  standard offpage *
  page29_i178
#ISCELL
  logical_power universal_power *
  page29_i179
#ISCELL
  standard offpage *
  page29_i181
#ISCELL
  logical_power universal_gnd *
  page29_i182
#ISCELL
  logical_power universal_gnd *
  page29_i183
#CELL
  pure_quanta q_res *
  page29_i184
#ISCELL
  logical_power universal_gnd *
  page29_i185
#ISCELL
  standard offpage *
  page29_i186
#ISCELL
  standard offpage *
  page29_i187
#ISCELL
  standard offpage *
  page29_i188
#ISCELL
  standard offpage *
  page29_i189
#ISCELL
  standard offpage *
  page29_i190
#ISCELL
  standard offpage *
  page29_i192
#CELL
  pure_quanta q_cap *
  page29_i193
#CELL
  pure_quanta q_cap *
  page29_i194
#ISCELL
  logical_power universal_gnd *
  page29_i195
#ISCELL
  logical_power universal_power *
  page29_i197
#ISCELL
  standard offpage *
  page29_i199
#ISCELL
  logical_power universal_gnd *
  page29_i200
#CELL
  pure_quanta q_res *
  page29_i201
#CELL
  pure_quanta 2n7002a7 *
  page29_i202
#ISCELL
  logical_power vccaux15 *
  page29_i203
#CELL
  pure_quanta q_res *
  page29_i204
#ISCELL
  standard offpage *
  page29_i205
#CELL
  pure_quanta pi3pcie3212zbex *
  page29_i206
#ISCELL
  standard offpage *
  page29_i207
#ISCELL
  standard offpage *
  page29_i208
#ISCELL
  standard offpage *
  page29_i209
#ISCELL
  standard offpage *
  page29_i210
#CELL
  pure_quanta dt1240e04lp7 *
  page29_i211
#ISCELL
  logical_power universal_gnd *
  page29_i212
#ISCELL
  standard offpage *
  page29_i217
#ISCELL
  standard offpage *
  page29_i218
#CELL
  pure_quanta q_cap *
  page29_i219
#CELL
  pure_quanta q_cap *
  page29_i220
#CELL
  pure_quanta conn9_gsb3111315hr *
  page29_i221
#CELL
  pure_quanta q_res *
  page29_i222
#ISCELL
  logical_power universal_power *
  page29_i95
#CELL
  pure_quanta q_res *
  page29_i96
#ISCELL
  standard offpage *
  page29_i97
#ISCELL
  standard offpage *
  page29_i98
#CELL
  pure_quanta prtr5v0u2x *
  page29_i99
#ISCELL
  logical_power design_note *
  *
#ISCELL
  mstr_misc dns *
  *
#ISCELL
  pure_quanta quanta_title_block_c *
  *
#ISCELL
  standard offpage *
  page30_i104
#ISCELL
  standard offpage *
  page30_i105
#ISCELL
  standard offpage *
  page30_i107
#ISCELL
  standard offpage *
  page30_i108
#ISCELL
  logical_power universal_gnd *
  page30_i117
#ISCELL
  standard offpage *
  page30_i142
#ISCELL
  standard offpage *
  page30_i143
#CELL
  pure_quanta q_res *
  page30_i146
#CELL
  pure_quanta q_res *
  page30_i147
#CELL
  pure_quanta q_res *
  page30_i148
#CELL
  pure_quanta q_cap *
  page30_i151
#ISCELL
  logical_power universal_gnd *
  page30_i152
#ISCELL
  logical_power universal_gnd *
  page30_i154
#ISCELL
  standard offpage *
  page30_i172
#ISCELL
  standard offpage *
  page30_i173
#ISCELL
  standard offpage *
  page30_i175
#ISCELL
  standard offpage *
  page30_i176
#ISCELL
  standard offpage *
  page30_i179
#ISCELL
  standard offpage *
  page30_i181
#ISCELL
  logical_power universal_gnd *
  page30_i182
#CELL
  pure_quanta sconn3_21291035br2 *
  page30_i184
#CELL
  pure_quanta q_res *
  page30_i192
#CELL
  pure_quanta q_res *
  page30_i195
#CELL
  pure_quanta q_res *
  page30_i197
#ISCELL
  logical_power universal_power *
  page30_i207
#ISCELL
  logical_power universal_power *
  page30_i208
#ISCELL
  logical_power universal_power *
  page30_i211
#ISCELL
  logical_power universal_power *
  page30_i214
#ISCELL
  logical_power universal_power *
  page30_i217
#ISCELL
  standard offpage *
  page30_i219
#ISCELL
  standard offpage *
  page30_i220
#CELL
  pure_quanta q_res *
  page30_i221
#CELL
  pure_quanta q_res *
  page30_i225
#CELL
  pure_quanta q_res *
  page30_i226
#ISCELL
  logical_power universal_power *
  page30_i227
#ISCELL
  logical_power universal_gnd *
  page30_i228
#CELL
  pure_quanta q_cap *
  page30_i229
#ISCELL
  logical_power universal_power *
  page30_i230
#CELL
  pure_quanta q_res *
  page30_i231
#ISCELL
  logical_power universal_gnd *
  page30_i233
#ISCELL
  standard offpage *
  page30_i234
#ISCELL
  standard offpage *
  page30_i235
#ISCELL
  logical_power universal_power *
  page30_i236
#CELL
  pure_quanta q_res *
  page30_i237
#ISCELL
  logical_power universal_power *
  page30_i238
#CELL
  pure_quanta q_res *
  page30_i239
#CELL
  pure_quanta 74lvc2g07dw7 *
  page30_i246
#CELL
  pure_quanta 74lvc2g07dw7 *
  page30_i247
#CELL
  pure_quanta fsa3357k8x *
  page30_i250
#CELL
  pure_quanta fsa3357k8x *
  page30_i251
#ISCELL
  standard offpage *
  page30_i252
#ISCELL
  logical_power universal_gnd *
  page30_i253
#CELL
  pure_quanta q_cap *
  page30_i254
#ISCELL
  logical_power universal_power *
  page30_i255
#ISCELL
  logical_power universal_gnd *
  page30_i256
#ISCELL
  standard offpage *
  page30_i258
#ISCELL
  standard offpage *
  page30_i259
#ISCELL
  logical_power universal_power *
  page30_i260
#CELL
  pure_quanta q_cap *
  page30_i261
#ISCELL
  logical_power universal_gnd *
  page30_i262
#ISCELL
  standard offpage *
  page30_i263
#ISCELL
  standard offpage *
  page30_i264
#ISCELL
  standard offpage *
  page30_i265
#CELL
  pure_quanta q_res *
  page30_i266
#CELL
  pure_quanta q_res *
  page30_i267
#ISCELL
  mstr_misc dns *
  *
#ISCELL
  pure_quanta quanta_title_block_c *
  *
#ISCELL
  standard offpage *
  page31_i1
#ISCELL
  logical_power universal_gnd *
  page31_i10
#CELL
  pure_quanta q_cap *
  page31_i11
#ISCELL
  logical_power universal_power *
  page31_i12
#ISCELL
  logical_power universal_gnd *
  page31_i16
#CELL
  pure_quanta q_cap *
  page31_i17
#ISCELL
  logical_power universal_power *
  page31_i18
#ISCELL
  standard offpage *
  page31_i19
#ISCELL
  standard offpage *
  page31_i2
#ISCELL
  standard offpage *
  page31_i20
#ISCELL
  standard offpage *
  page31_i21
#ISCELL
  standard offpage *
  page31_i22
#CELL
  pure_quanta nc7sb3157 *
  page31_i23
#CELL
  pure_quanta nc7sb3157 *
  page31_i24
#CELL
  pure_quanta q_res *
  page31_i25
#ISCELL
  logical_power universal_power *
  page31_i26
#CELL
  pure_quanta nc7sb3157 *
  page31_i27
#ISCELL
  standard offpage *
  page31_i28
#ISCELL
  standard offpage *
  page31_i3
#ISCELL
  logical_power universal_power *
  page31_i30
#CELL
  pure_quanta q_cap *
  page31_i31
#ISCELL
  logical_power universal_gnd *
  page31_i32
#ISCELL
  logical_power universal_gnd *
  page31_i33
#CELL
  pure_quanta nc7sb3157 *
  page31_i38
#ISCELL
  standard offpage *
  page31_i4
#ISCELL
  logical_power universal_gnd *
  page31_i43
#ISCELL
  logical_power universal_gnd *
  page31_i44
#CELL
  pure_quanta q_cap *
  page31_i45
#ISCELL
  logical_power universal_power *
  page31_i46
#ISCELL
  standard offpage *
  page31_i47
#ISCELL
  standard offpage *
  page31_i48
#ISCELL
  standard offpage *
  page31_i49
#ISCELL
  logical_power universal_gnd *
  page31_i52
#ISCELL
  logical_power universal_power *
  page31_i54
#ISCELL
  standard offpage *
  page31_i56
#ISCELL
  standard offpage *
  page31_i59
#CELL
  pure_quanta sconn3_212h9103gbr1 *
  page31_i61
#ISCELL
  standard offpage *
  page31_i62
#ISCELL
  standard offpage *
  page31_i63
#ISCELL
  standard offpage *
  page31_i68
#ISCELL
  standard offpage *
  page31_i69
#ISCELL
  logical_power universal_gnd *
  page31_i7
#CELL
  pure_quanta q_res *
  page31_i70
#CELL
  pure_quanta q_res *
  page31_i71
#CELL
  pure_quanta q_res *
  page31_i72
#CELL
  pure_quanta q_res *
  page31_i73
#CELL
  pure_quanta q_res *
  page31_i74
#CELL
  pure_quanta q_res *
  page31_i75
#CELL
  pure_quanta q_res *
  page31_i76
#CELL
  pure_quanta q_res *
  page31_i77
#CELL
  pure_quanta q_res *
  page31_i78
#CELL
  pure_quanta q_res *
  page31_i79
#CELL
  pure_quanta q_res *
  page31_i80
#ISCELL
  logical_power universal_power *
  page31_i81
#ISCELL
  logical_power universal_gnd *
  page31_i9
#ISCELL
  logical_power design_note *
  *
#ISCELL
  mstr_misc dns *
  *
#ISCELL
  pure_quanta quanta_title_block_c *
  *
#ISCELL
  standard offpage *
  page32_i100
#ISCELL
  standard offpage *
  page32_i101
#ISCELL
  standard offpage *
  page32_i102
#CELL
  pure_quanta q_res *
  page32_i103
#CELL
  pure_quanta q_res *
  page32_i104
#CELL
  pure_quanta q_res *
  page32_i105
#CELL
  pure_quanta q_res *
  page32_i106
#CELL
  pure_quanta q_res *
  page32_i107
#ISCELL
  logical_power universal_power *
  page32_i108
#ISCELL
  standard offpage *
  page32_i109
#ISCELL
  standard offpage *
  page32_i110
#ISCELL
  standard offpage *
  page32_i111
#ISCELL
  standard offpage *
  page32_i112
#ISCELL
  logical_power universal_gnd *
  page32_i113
#CELL
  pure_quanta q_res *
  page32_i117
#ISCELL
  logical_power universal_power *
  page32_i118
#CELL
  pure_quanta q_res *
  page32_i119
#CELL
  pure_quanta q_res *
  page32_i120
#ISCELL
  logical_power universal_gnd *
  page32_i123
#ISCELL
  standard offpage *
  page32_i124
#CELL
  pure_quanta q_res *
  page32_i126
#CELL
  pure_quanta q_res *
  page32_i127
#CELL
  pure_quanta q_res *
  page32_i128
#CELL
  pure_quanta q_res *
  page32_i129
#CELL
  pure_quanta q_res *
  page32_i131
#CELL
  pure_quanta conn8_210hp1080br1 *
  page32_i132
#CELL
  pure_quanta q_res *
  page32_i140
#CELL
  pure_quanta q_res *
  page32_i141
#ISCELL
  logical_power universal_gnd *
  page32_i142
#CELL
  pure_quanta q_res *
  page32_i143
#CELL
  pure_quanta schottky_12 *
  page32_i144
#ISCELL
  logical_power universal_gnd *
  page32_i145
#ISCELL
  standard offpage *
  page32_i17
#ISCELL
  logical_power universal_gnd *
  page32_i19
#ISCELL
  logical_power universal_power *
  page32_i20
#CELL
  pure_quanta q_cap *
  page32_i21
#CELL
  pure_quanta q_cap *
  page32_i22
#CELL
  pure_quanta q_res *
  page32_i23
#ISCELL
  standard offpage *
  page32_i41
#ISCELL
  standard offpage *
  page32_i42
#ISCELL
  standard offpage *
  page32_i43
#ISCELL
  standard offpage *
  page32_i44
#ISCELL
  standard offpage *
  page32_i45
#ISCELL
  standard offpage *
  page32_i49
#ISCELL
  standard offpage *
  page32_i50
#ISCELL
  standard offpage *
  page32_i51
#ISCELL
  standard offpage *
  page32_i54
#ISCELL
  standard offpage *
  page32_i55
#ISCELL
  standard offpage *
  page32_i56
#ISCELL
  standard offpage *
  page32_i57
#ISCELL
  standard offpage *
  page32_i74
#ISCELL
  standard offpage *
  page32_i75
#ISCELL
  standard offpage *
  page32_i76
#ISCELL
  standard offpage *
  page32_i77
#CELL
  pure_quanta q_res *
  page32_i78
#CELL
  pure_quanta q_res *
  page32_i80
#CELL
  pure_quanta q_res *
  page32_i81
#ISCELL
  standard offpage *
  page32_i82
#ISCELL
  standard offpage *
  page32_i83
#ISCELL
  standard offpage *
  page32_i84
#ISCELL
  standard offpage *
  page32_i85
#ISCELL
  standard offpage *
  page32_i86
#CELL
  pure_quanta q_res *
  page32_i87
#CELL
  pure_quanta q_res *
  page32_i88
#ISCELL
  standard offpage *
  page32_i89
#ISCELL
  standard offpage *
  page32_i90
#ISCELL
  standard offpage *
  page32_i91
#ISCELL
  standard offpage *
  page32_i92
#ISCELL
  standard offpage *
  page32_i93
#CELL
  pure_quanta q_res *
  page32_i94
#CELL
  pure_quanta q_res *
  page32_i95
#CELL
  pure_quanta q_res *
  page32_i96
#CELL
  pure_quanta q_res *
  page32_i97
#ISCELL
  standard offpage *
  page32_i98
#ISCELL
  standard offpage *
  page32_i99
#ISCELL
  pure_quanta quanta_title_block_c *
  *
#ISCELL
  pure_quanta quanta_title_block_c *
  *
#CELL
  pure_quanta lcmxo3lf2100c5bg256c *
  page34_i1
#ISCELL
  standard offpage *
  page34_i10
#ISCELL
  standard offpage *
  page34_i105
#ISCELL
  standard offpage *
  page34_i106
#ISCELL
  standard offpage *
  page34_i107
#ISCELL
  standard offpage *
  page34_i11
#ISCELL
  standard offpage *
  page34_i111
#ISCELL
  standard offpage *
  page34_i112
#ISCELL
  standard offpage *
  page34_i113
#ISCELL
  standard offpage *
  page34_i114
#CELL
  pure_quanta q_res *
  page34_i115
#CELL
  pure_quanta q_res *
  page34_i116
#CELL
  pure_quanta q_res *
  page34_i117
#ISCELL
  logical_power universal_power *
  page34_i118
#CELL
  pure_quanta q_res *
  page34_i119
#ISCELL
  standard offpage *
  page34_i12
#ISCELL
  logical_power universal_power *
  page34_i120
#ISCELL
  logical_power universal_gnd *
  page34_i121
#CELL
  pure_quanta q_cap *
  page34_i122
#ISCELL
  logical_power universal_power *
  page34_i123
#ISCELL
  logical_power universal_gnd *
  page34_i124
#ISCELL
  standard offpage *
  page34_i125
#CELL
  pure_quanta q_res *
  page34_i126
#CELL
  pure_quanta osc4_7x25000018 *
  page34_i127
#ISCELL
  logical_power universal_power *
  page34_i128
#ISCELL
  logical_power universal_power *
  page34_i129
#ISCELL
  standard offpage *
  page34_i13
#ISCELL
  standard offpage *
  page34_i130
#ISCELL
  logical_power universal_power *
  page34_i136
#CELL
  pure_quanta q_res *
  page34_i137
#ISCELL
  logical_power universal_power *
  page34_i138
#CELL
  pure_quanta q_res *
  page34_i139
#CELL
  pure_quanta q_cap *
  page34_i140
#ISCELL
  logical_power universal_gnd *
  page34_i141
#ISCELL
  logical_power universal_power *
  page34_i143
#CELL
  pure_quanta q_cap *
  page34_i144
#ISCELL
  standard offpage *
  page34_i145
#CELL
  pure_quanta q_res *
  page34_i147
#ISCELL
  standard offpage *
  page34_i148
#ISCELL
  standard offpage *
  page34_i15
#CELL
  pure_quanta q_res *
  page34_i150
#ISCELL
  standard offpage *
  page34_i151
#ISCELL
  standard offpage *
  page34_i152
#ISCELL
  standard offpage *
  page34_i153
#CELL
  pure_quanta q_res *
  page34_i155
#CELL
  pure_quanta q_res *
  page34_i156
#CELL
  pure_quanta q_res *
  page34_i157
#CELL
  pure_quanta q_res *
  page34_i158
#CELL
  pure_quanta q_res *
  page34_i159
#ISCELL
  standard offpage *
  page34_i16
#CELL
  pure_quanta q_res *
  page34_i160
#CELL
  pure_quanta q_res *
  page34_i161
#CELL
  pure_quanta q_res *
  page34_i162
#CELL
  pure_quanta q_res *
  page34_i163
#CELL
  pure_quanta q_res *
  page34_i164
#CELL
  pure_quanta q_res *
  page34_i165
#CELL
  pure_quanta q_res *
  page34_i166
#CELL
  pure_quanta q_res *
  page34_i167
#CELL
  pure_quanta q_res *
  page34_i168
#CELL
  pure_quanta q_res *
  page34_i17
#ISCELL
  logical_power vccaux15 *
  page34_i18
#ISCELL
  standard offpage *
  page34_i19
#ISCELL
  standard offpage *
  page34_i20
#ISCELL
  standard offpage *
  page34_i21
#ISCELL
  standard offpage *
  page34_i23
#ISCELL
  standard offpage *
  page34_i24
#ISCELL
  standard offpage *
  page34_i25
#ISCELL
  standard offpage *
  page34_i26
#ISCELL
  standard offpage *
  page34_i27
#ISCELL
  standard offpage *
  page34_i30
#CELL
  pure_quanta q_res *
  page34_i35
#CELL
  pure_quanta q_res *
  page34_i37
#ISCELL
  standard offpage *
  page34_i42
#ISCELL
  standard offpage *
  page34_i43
#ISCELL
  standard offpage *
  page34_i44
#ISCELL
  standard offpage *
  page34_i45
#ISCELL
  standard offpage *
  page34_i77
#ISCELL
  standard offpage *
  page34_i78
#ISCELL
  standard offpage *
  page34_i79
#ISCELL
  standard offpage *
  page34_i8
#ISCELL
  standard offpage *
  page34_i80
#ISCELL
  standard offpage *
  page34_i81
#ISCELL
  standard offpage *
  page34_i82
#ISCELL
  standard offpage *
  page34_i83
#ISCELL
  standard offpage *
  page34_i84
#ISCELL
  standard offpage *
  page34_i85
#ISCELL
  standard offpage *
  page34_i86
#ISCELL
  standard offpage *
  page34_i87
#ISCELL
  standard offpage *
  page34_i88
#ISCELL
  standard offpage *
  page34_i89
#ISCELL
  standard offpage *
  page34_i9
#ISCELL
  standard offpage *
  page34_i93
#ISCELL
  standard offpage *
  page34_i96
#ISCELL
  mstr_misc dns *
  *
#ISCELL
  pure_quanta quanta_title_block_c *
  *
#CELL
  pure_quanta lcmxo3lf2100c5bg256c *
  page35_i1
#ISCELL
  standard offpage *
  page35_i10
#CELL
  pure_quanta q_res *
  page35_i100
#ISCELL
  standard offpage *
  page35_i106
#ISCELL
  standard offpage *
  page35_i109
#ISCELL
  standard offpage *
  page35_i11
#ISCELL
  standard offpage *
  page35_i110
#ISCELL
  standard offpage *
  page35_i111
#ISCELL
  standard offpage *
  page35_i114
#ISCELL
  standard offpage *
  page35_i115
#ISCELL
  standard offpage *
  page35_i116
#ISCELL
  standard offpage *
  page35_i117
#ISCELL
  standard offpage *
  page35_i118
#ISCELL
  standard offpage *
  page35_i119
#ISCELL
  standard offpage *
  page35_i12
#ISCELL
  standard offpage *
  page35_i121
#ISCELL
  logical_power universal_power *
  page35_i122
#ISCELL
  logical_power universal_power *
  page35_i123
#ISCELL
  standard offpage *
  page35_i124
#ISCELL
  standard offpage *
  page35_i125
#ISCELL
  standard offpage *
  page35_i13
#CELL
  pure_quanta q_res *
  page35_i131
#ISCELL
  standard offpage *
  page35_i132
#ISCELL
  logical_power vccaux15 *
  page35_i133
#ISCELL
  standard offpage *
  page35_i134
#CELL
  pure_quanta q_res *
  page35_i136
#CELL
  pure_quanta q_res *
  page35_i137
#CELL
  pure_quanta q_res *
  page35_i138
#CELL
  pure_quanta q_res *
  page35_i139
#ISCELL
  standard offpage *
  page35_i14
#CELL
  pure_quanta q_res *
  page35_i140
#CELL
  pure_quanta q_res *
  page35_i141
#CELL
  pure_quanta q_res *
  page35_i142
#CELL
  pure_quanta q_res *
  page35_i143
#CELL
  pure_quanta q_res *
  page35_i144
#CELL
  pure_quanta q_res *
  page35_i145
#CELL
  pure_quanta q_res *
  page35_i146
#CELL
  pure_quanta q_res *
  page35_i147
#CELL
  pure_quanta q_res *
  page35_i148
#CELL
  pure_quanta q_res *
  page35_i149
#ISCELL
  standard offpage *
  page35_i15
#CELL
  pure_quanta q_diode *
  page35_i150
#CELL
  pure_quanta q_res *
  page35_i151
#ISCELL
  logical_power vccaux15 *
  page35_i152
#ISCELL
  standard offpage *
  page35_i153
#ISCELL
  standard offpage *
  page35_i154
#ISCELL
  standard offpage *
  page35_i16
#ISCELL
  standard offpage *
  page35_i17
#ISCELL
  standard offpage *
  page35_i18
#CELL
  pure_quanta q_res *
  page35_i2
#ISCELL
  standard offpage *
  page35_i21
#ISCELL
  standard offpage *
  page35_i23
#CELL
  pure_quanta q_res *
  page35_i3
#CELL
  pure_quanta q_res *
  page35_i4
#CELL
  pure_quanta q_res *
  page35_i5
#ISCELL
  standard offpage *
  page35_i52
#ISCELL
  standard offpage *
  page35_i53
#ISCELL
  standard offpage *
  page35_i54
#ISCELL
  standard offpage *
  page35_i55
#ISCELL
  standard offpage *
  page35_i57
#ISCELL
  standard offpage *
  page35_i58
#ISCELL
  standard offpage *
  page35_i59
#ISCELL
  standard offpage *
  page35_i60
#ISCELL
  standard offpage *
  page35_i61
#ISCELL
  standard offpage *
  page35_i62
#ISCELL
  standard offpage *
  page35_i63
#CELL
  pure_quanta q_res *
  page35_i76
#ISCELL
  standard offpage *
  page35_i8
#CELL
  pure_quanta q_res *
  page35_i80
#ISCELL
  standard offpage *
  page35_i84
#ISCELL
  standard offpage *
  page35_i85
#CELL
  pure_quanta q_res *
  page35_i88
#ISCELL
  standard offpage *
  page35_i89
#ISCELL
  standard offpage *
  page35_i9
#CELL
  pure_quanta q_res *
  page35_i95
#CELL
  pure_quanta q_res *
  page35_i98
#CELL
  pure_quanta q_res *
  page35_i99
#ISCELL
  pure_quanta quanta_title_block_c *
  *
#CELL
  pure_quanta lcmxo3lf2100c5bg256c *
  page36_i1
#CELL
  pure_quanta q_res *
  page36_i10
#ISCELL
  standard offpage *
  page36_i14
#ISCELL
  standard offpage *
  page36_i16
#ISCELL
  standard offpage *
  page36_i17
#ISCELL
  standard offpage *
  page36_i18
#ISCELL
  standard offpage *
  page36_i19
#CELL
  pure_quanta q_res *
  page36_i2
#ISCELL
  standard offpage *
  page36_i20
#ISCELL
  standard offpage *
  page36_i21
#ISCELL
  standard offpage *
  page36_i22
#ISCELL
  standard offpage *
  page36_i23
#ISCELL
  standard offpage *
  page36_i27
#ISCELL
  standard offpage *
  page36_i28
#ISCELL
  standard offpage *
  page36_i29
#CELL
  pure_quanta q_res *
  page36_i3
#ISCELL
  standard offpage *
  page36_i30
#CELL
  pure_quanta q_res *
  page36_i33
#CELL
  pure_quanta q_res *
  page36_i34
#CELL
  pure_quanta q_res *
  page36_i35
#CELL
  pure_quanta q_res *
  page36_i36
#ISCELL
  logical_power universal_power *
  page36_i37
#ISCELL
  logical_power universal_power *
  page36_i38
#CELL
  pure_quanta q_res *
  page36_i42
#CELL
  pure_quanta q_res *
  page36_i43
#ISCELL
  standard offpage *
  page36_i44
#ISCELL
  standard offpage *
  page36_i45
#CELL
  pure_quanta q_res *
  page36_i46
#CELL
  pure_quanta q_res *
  page36_i47
#ISCELL
  standard offpage *
  page36_i49
#CELL
  pure_quanta q_res *
  page36_i50
#ISCELL
  logical_power universal_power *
  page36_i51
#ISCELL
  standard offpage *
  page36_i52
#ISCELL
  standard offpage *
  page36_i54
#ISCELL
  standard offpage *
  page36_i55
#ISCELL
  standard offpage *
  page36_i56
#CELL
  pure_quanta q_res *
  page36_i57
#CELL
  pure_quanta q_res *
  page36_i58
#ISCELL
  standard offpage *
  page36_i61
#ISCELL
  standard offpage *
  page36_i62
#ISCELL
  standard offpage *
  page36_i63
#ISCELL
  standard offpage *
  page36_i64
#ISCELL
  standard offpage *
  page36_i65
#ISCELL
  standard offpage *
  page36_i66
#ISCELL
  standard offpage *
  page36_i67
#ISCELL
  standard offpage *
  page36_i68
#ISCELL
  standard offpage *
  page36_i69
#CELL
  pure_quanta q_res *
  page36_i7
#ISCELL
  standard offpage *
  page36_i74
#ISCELL
  standard offpage *
  page36_i75
#ISCELL
  standard offpage *
  page36_i76
#ISCELL
  standard offpage *
  page36_i77
#CELL
  pure_quanta q_res *
  page36_i78
#ISCELL
  standard offpage *
  page36_i79
#CELL
  pure_quanta q_res *
  page36_i8
#CELL
  pure_quanta q_res *
  page36_i80
#CELL
  pure_quanta q_res *
  page36_i81
#CELL
  pure_quanta q_res *
  page36_i82
#CELL
  pure_quanta q_res *
  page36_i9
#ISCELL
  pure_quanta quanta_title_block_c *
  *
#CELL
  pure_quanta lcmxo3lf2100c5bg256c *
  page37_i1
#ISCELL
  logical_power universal_power *
  page37_i3
#ISCELL
  pure_quanta quanta_title_block_c *
  *
#CELL
  pure_quanta lcmxo3lf2100c5bg256c *
  page38_i1
#ISCELL
  logical_power universal_power *
  page38_i3
#ISCELL
  pure_quanta quanta_title_block_c *
  *
#CELL
  pure_quanta lcmxo3lf2100c5bg256c *
  page39_i1
#ISCELL
  logical_power universal_power *
  page39_i3
#ISCELL
  pure_quanta quanta_title_block_c *
  *
#CELL
  pure_quanta lcmxo3lf2100c5bg256c *
  page40_i1
#ISCELL
  logical_power universal_gnd *
  page40_i2
#ISCELL
  logical_power universal_power *
  page40_i3
#ISCELL
  mstr_misc dns *
  *
#ISCELL
  pure_quanta quanta_title_block_c *
  *
#CELL
  pure_quanta q_cap *
  page41_i1
#ISCELL
  logical_power universal_gnd *
  page41_i100
#CELL
  pure_quanta q_cap *
  page41_i101
#ISCELL
  logical_power universal_power *
  page41_i104
#CELL
  pure_quanta q_inductor *
  page41_i107
#CELL
  pure_quanta q_cap *
  page41_i108
#CELL
  pure_quanta q_cap *
  page41_i109
#ISCELL
  logical_power universal_power *
  page41_i11
#ISCELL
  logical_power universal_gnd *
  page41_i112
#ISCELL
  logical_power universal_power *
  page41_i114
#CELL
  pure_quanta q_cap *
  page41_i115
#CELL
  pure_quanta q_cap *
  page41_i116
#CELL
  pure_quanta q_cap *
  page41_i117
#CELL
  pure_quanta q_cap *
  page41_i118
#CELL
  pure_quanta q_cap *
  page41_i119
#CELL
  pure_quanta q_cap *
  page41_i122
#CELL
  pure_quanta q_cap *
  page41_i123
#CELL
  pure_quanta q_cap *
  page41_i124
#CELL
  pure_quanta q_cap *
  page41_i125
#CELL
  pure_quanta q_cap *
  page41_i126
#ISCELL
  logical_power universal_power *
  page41_i18
#ISCELL
  logical_power universal_gnd *
  page41_i24
#ISCELL
  logical_power universal_power *
  page41_i26
#ISCELL
  logical_power universal_power *
  page41_i27
#ISCELL
  logical_power universal_gnd *
  page41_i29
#ISCELL
  logical_power universal_power *
  page41_i35
#ISCELL
  logical_power universal_power *
  page41_i40
#ISCELL
  logical_power universal_gnd *
  page41_i42
#ISCELL
  logical_power universal_power *
  page41_i48
#ISCELL
  logical_power universal_power *
  page41_i53
#ISCELL
  logical_power universal_gnd *
  page41_i55
#ISCELL
  logical_power universal_power *
  page41_i6
#ISCELL
  logical_power universal_power *
  page41_i61
#ISCELL
  logical_power universal_power *
  page41_i66
#ISCELL
  logical_power universal_gnd *
  page41_i68
#ISCELL
  logical_power universal_gnd *
  page41_i7
#CELL
  pure_quanta q_res *
  page41_i71
#CELL
  pure_quanta q_res *
  page41_i72
#CELL
  pure_quanta q_res *
  page41_i73
#CELL
  pure_quanta q_res *
  page41_i74
#CELL
  pure_quanta q_res *
  page41_i75
#CELL
  pure_quanta q_res *
  page41_i76
#CELL
  pure_quanta q_cap *
  page41_i77
#CELL
  pure_quanta q_cap *
  page41_i78
#CELL
  pure_quanta q_cap *
  page41_i79
#CELL
  pure_quanta q_cap *
  page41_i8
#CELL
  pure_quanta q_cap *
  page41_i80
#CELL
  pure_quanta q_cap *
  page41_i81
#CELL
  pure_quanta q_cap *
  page41_i82
#CELL
  pure_quanta q_cap *
  page41_i83
#CELL
  pure_quanta q_cap *
  page41_i84
#CELL
  pure_quanta q_cap *
  page41_i85
#CELL
  pure_quanta q_cap *
  page41_i86
#CELL
  pure_quanta q_cap *
  page41_i87
#CELL
  pure_quanta q_cap *
  page41_i88
#CELL
  pure_quanta q_cap *
  page41_i89
#CELL
  pure_quanta q_cap *
  page41_i90
#CELL
  pure_quanta q_cap *
  page41_i91
#CELL
  pure_quanta q_cap *
  page41_i92
#CELL
  pure_quanta q_cap *
  page41_i93
#CELL
  pure_quanta q_cap *
  page41_i94
#CELL
  pure_quanta q_cap *
  page41_i95
#CELL
  pure_quanta q_cap *
  page41_i96
#ISCELL
  logical_power universal_power *
  page41_i97
#ISCELL
  logical_power universal_gnd *
  page41_i98
#CELL
  pure_quanta q_cap *
  page41_i99
#ISCELL
  mstr_misc dns *
  *
#ISCELL
  pure_quanta quanta_title_block_c *
  *
#ISCELL
  standard offpage *
  page42_i12
#CELL
  pure_quanta q_res *
  page42_i13
#ISCELL
  standard offpage *
  page42_i26
#CELL
  pure_quanta q_res *
  page42_i27
#ISCELL
  standard offpage *
  page42_i28
#CELL
  pure_quanta q_res *
  page42_i29
#ISCELL
  logical_power universal_power *
  page42_i3
#ISCELL
  standard offpage *
  page42_i36
#CELL
  pure_quanta q_res *
  page42_i37
#ISCELL
  standard offpage *
  page42_i38
#CELL
  pure_quanta q_res *
  page42_i39
#ISCELL
  standard offpage *
  page42_i52
#CELL
  pure_quanta q_res *
  page42_i53
#ISCELL
  logical_power universal_power *
  page42_i54
#ISCELL
  standard offpage *
  page42_i55
#CELL
  pure_quanta q_res *
  page42_i56
#ISCELL
  logical_power universal_gnd *
  page42_i57
#CELL
  pure_quanta q_res *
  page42_i58
#ISCELL
  standard offpage *
  page42_i6
#ISCELL
  standard offpage *
  page42_i60
#CELL
  pure_quanta q_res *
  page42_i61
#ISCELL
  standard offpage *
  page42_i62
#CELL
  pure_quanta q_res *
  page42_i63
#ISCELL
  standard offpage *
  page42_i64
#CELL
  pure_quanta q_res *
  page42_i65
#ISCELL
  standard offpage *
  page42_i66
#CELL
  pure_quanta q_res *
  page42_i67
#CELL
  pure_quanta q_res *
  page42_i7
#ISCELL
  pure_quanta quanta_title_block_c *
  *
#ISCELL
  mstr_misc dns *
  *
#ISCELL
  pure_quanta quanta_title_block_c *
  *
#ISCELL
  standard offpage *
  page44_i262
#ISCELL
  standard offpage *
  page44_i263
#CELL
  pure_quanta idtqs3vh257pag *
  page44_i271
#ISCELL
  logical_power universal_gnd *
  page44_i272
#ISCELL
  standard offpage *
  page44_i273
#ISCELL
  standard offpage *
  page44_i274
#ISCELL
  standard offpage *
  page44_i275
#ISCELL
  logical_power p3v3_aux *
  page44_i276
#ISCELL
  logical_power universal_gnd *
  page44_i277
#CELL
  pure_quanta q_cap *
  page44_i278
#ISCELL
  standard offpage *
  page44_i279
#ISCELL
  standard offpage *
  page44_i280
#ISCELL
  standard offpage *
  page44_i281
#ISCELL
  standard offpage *
  page44_i282
#ISCELL
  standard offpage *
  page44_i283
#ISCELL
  standard offpage *
  page44_i284
#ISCELL
  standard offpage *
  page44_i285
#ISCELL
  standard offpage *
  page44_i286
#ISCELL
  standard offpage *
  page44_i287
#ISCELL
  standard offpage *
  page44_i288
#ISCELL
  standard offpage *
  page44_i289
#ISCELL
  standard offpage *
  page44_i290
#ISCELL
  standard offpage *
  page44_i291
#CELL
  pure_quanta q_cap *
  page44_i292
#ISCELL
  logical_power universal_gnd *
  page44_i293
#ISCELL
  logical_power universal_gnd *
  page44_i294
#ISCELL
  logical_power p3v3_aux *
  page44_i295
#CELL
  pure_quanta idtqs3vh257pag *
  page44_i296
#ISCELL
  standard offpage *
  page44_i305
#ISCELL
  standard offpage *
  page44_i306
#ISCELL
  standard offpage *
  page44_i309
#ISCELL
  standard offpage *
  page44_i310
#CELL
  pure_quanta q_res *
  page44_i311
#ISCELL
  logical_power universal_gnd *
  page44_i312
#CELL
  pure_quanta q_res *
  page44_i313
#ISCELL
  logical_power universal_gnd *
  page44_i314
#CELL
  pure_quanta q_res *
  page44_i315
#ISCELL
  logical_power p3v3_aux *
  page44_i316
#ISCELL
  standard offpage *
  page44_i317
#ISCELL
  standard offpage *
  page44_i318
#ISCELL
  standard offpage *
  page44_i319
#ISCELL
  standard offpage *
  page44_i320
#ISCELL
  standard offpage *
  page44_i321
#ISCELL
  standard offpage *
  page44_i323
#ISCELL
  standard offpage *
  page44_i324
#ISCELL
  standard offpage *
  page44_i325
#ISCELL
  standard offpage *
  page44_i326
#ISCELL
  standard offpage *
  page44_i327
#ISCELL
  standard offpage *
  page44_i328
#ISCELL
  standard offpage *
  page44_i329
#CELL
  pure_quanta q_res *
  page44_i330
#CELL
  pure_quanta q_res *
  page44_i331
#CELL
  pure_quanta q_res *
  page44_i332
#CELL
  pure_quanta q_res *
  page44_i333
#CELL
  pure_quanta q_res *
  page44_i334
#CELL
  pure_quanta q_res *
  page44_i336
#CELL
  pure_quanta q_res *
  page44_i339
#CELL
  pure_quanta q_res *
  page44_i342
#ISCELL
  standard offpage *
  page44_i343
#ISCELL
  standard offpage *
  page44_i344
#ISCELL
  standard offpage *
  page44_i345
#ISCELL
  standard offpage *
  page44_i346
#ISCELL
  standard offpage *
  page44_i347
#ISCELL
  standard offpage *
  page44_i349
#ISCELL
  standard offpage *
  page44_i350
#ISCELL
  standard offpage *
  page44_i351
#ISCELL
  standard offpage *
  page44_i352
#ISCELL
  standard offpage *
  page44_i353
#ISCELL
  standard offpage *
  page44_i354
#ISCELL
  standard offpage *
  page44_i355
#ISCELL
  standard offpage *
  page44_i356
#ISCELL
  standard offpage *
  page44_i358
#ISCELL
  standard offpage *
  page44_i359
#CELL
  pure_quanta q_res *
  page44_i360
#ISCELL
  standard offpage *
  page44_i361
#CELL
  pure_quanta q_res *
  page44_i362
#CELL
  pure_quanta q_res *
  page44_i363
#CELL
  pure_quanta q_res *
  page44_i364
#CELL
  pure_quanta q_res *
  page44_i365
#CELL
  pure_quanta q_res *
  page44_i366
#ISCELL
  logical_power bom_note *
  *
#ISCELL
  logical_power cad_note *
  *
#ISCELL
  mstr_misc dns *
  *
#ISCELL
  pure_quanta quanta_title_block_c *
  *
#ISCELL
  standard offpage *
  page45_i1
#CELL
  pure_quanta q_res *
  page45_i19
#ISCELL
  standard offpage *
  page45_i2
#CELL
  pure_quanta q_res *
  page45_i20
#CELL
  pure_quanta q_res *
  page45_i21
#CELL
  pure_quanta q_res *
  page45_i22
#CELL
  pure_quanta q_res *
  page45_i23
#CELL
  pure_quanta q_res *
  page45_i24
#ISCELL
  standard offpage *
  page45_i3
#CELL
  pure_quanta q_res *
  page45_i33
#CELL
  pure_quanta q_res *
  page45_i34
#CELL
  pure_quanta q_res *
  page45_i35
#ISCELL
  standard offpage *
  page45_i4
#ISCELL
  logical_power universal_gnd *
  page45_i40
#CELL
  pure_quanta q_cap *
  page45_i42
#ISCELL
  logical_power universal_gnd *
  page45_i43
#ISCELL
  logical_power universal_gnd *
  page45_i44
#CELL
  pure_quanta q_cap *
  page45_i45
#ISCELL
  logical_power universal_power *
  page45_i46
#CELL
  pure_quanta q_res *
  page45_i48
#ISCELL
  logical_power universal_power *
  page45_i49
#ISCELL
  standard offpage *
  page45_i5
#CELL
  pure_quanta q_res *
  page45_i51
#ISCELL
  logical_power universal_gnd *
  page45_i52
#CELL
  pure_quanta sconn16_acaspi006p06 *
  page45_i53
#CELL
  pure_quanta mx25l51245gmi10g *
  page45_i54
#ISCELL
  logical_power universal_power *
  page45_i55
#ISCELL
  logical_power universal_gnd *
  page45_i56
#ISCELL
  standard offpage *
  page45_i6
#ISCELL
  mstr_misc dns *
  *
#ISCELL
  pure_quanta quanta_title_block_c *
  *
#ISCELL
  standard offpage *
  page46_i100
#CELL
  pure_quanta q_cap *
  page46_i102
#CELL
  pure_quanta q_res *
  page46_i104
#CELL
  pure_quanta q_res *
  page46_i105
#CELL
  pure_quanta q_res *
  page46_i106
#ISCELL
  logical_power universal_power *
  page46_i107
#CELL
  pure_quanta q_cap *
  page46_i108
#ISCELL
  logical_power universal_gnd *
  page46_i109
#ISCELL
  logical_power universal_gnd *
  page46_i112
#CELL
  pure_quanta sconn11_9192031111lf *
  page46_i113
#CELL
  pure_quanta q_res *
  page46_i114
#CELL
  pure_quanta q_res *
  page46_i115
#CELL
  pure_quanta q_res *
  page46_i116
#CELL
  pure_quanta q_res *
  page46_i117
#CELL
  pure_quanta q_res *
  page46_i119
#ISCELL
  standard offpage *
  page46_i123
#ISCELL
  standard offpage *
  page46_i124
#ISCELL
  standard offpage *
  page46_i125
#ISCELL
  standard offpage *
  page46_i126
#ISCELL
  standard offpage *
  page46_i127
#CELL
  pure_quanta q_res *
  page46_i132
#ISCELL
  logical_power universal_power *
  page46_i133
#CELL
  pure_quanta q_res *
  page46_i134
#ISCELL
  logical_power universal_power *
  page46_i135
#CELL
  pure_quanta q_res *
  page46_i136
#CELL
  pure_quanta q_res *
  page46_i137
#ISCELL
  logical_power universal_power *
  page46_i138
#CELL
  pure_quanta q_res *
  page46_i139
#CELL
  pure_quanta q_res *
  page46_i140
#ISCELL
  standard offpage *
  page46_i141
#ISCELL
  standard offpage *
  page46_i143
#ISCELL
  logical_power universal_power *
  page46_i145
#ISCELL
  logical_power universal_power *
  page46_i146
#CELL
  pure_quanta q_res *
  page46_i147
#CELL
  pure_quanta sconn11_9192031111lf *
  page46_i56
#CELL
  pure_quanta q_res *
  page46_i58
#ISCELL
  standard offpage *
  page46_i59
#CELL
  pure_quanta q_res *
  page46_i60
#CELL
  pure_quanta q_res *
  page46_i65
#ISCELL
  standard offpage *
  page46_i66
#CELL
  pure_quanta q_cap *
  page46_i67
#ISCELL
  logical_power universal_power *
  page46_i68
#CELL
  pure_quanta q_cap *
  page46_i69
#ISCELL
  logical_power universal_gnd *
  page46_i70
#ISCELL
  logical_power universal_gnd *
  page46_i71
#ISCELL
  standard offpage *
  page46_i72
#ISCELL
  standard offpage *
  page46_i73
#CELL
  pure_quanta q_res *
  page46_i74
#CELL
  pure_quanta q_res *
  page46_i75
#ISCELL
  logical_power universal_power *
  page46_i77
#CELL
  pure_quanta q_res *
  page46_i78
#ISCELL
  standard offpage *
  page46_i81
#ISCELL
  standard offpage *
  page46_i82
#ISCELL
  standard offpage *
  page46_i83
#ISCELL
  logical_power universal_power *
  page46_i97
#CELL
  pure_quanta q_res *
  page46_i98
#ISCELL
  standard offpage *
  page46_i99
#ISCELL
  pure_quanta quanta_title_block_c *
  *
#CELL
  pure_quanta q_led *
  page47_i10
#CELL
  pure_quanta q_led *
  page47_i11
#CELL
  pure_quanta q_led *
  page47_i12
#CELL
  pure_quanta q_led *
  page47_i13
#CELL
  pure_quanta q_led *
  page47_i14
#CELL
  pure_quanta q_res *
  page47_i18
#CELL
  pure_quanta q_res *
  page47_i20
#CELL
  pure_quanta q_res *
  page47_i23
#CELL
  pure_quanta q_res *
  page47_i25
#CELL
  pure_quanta q_res *
  page47_i31
#CELL
  pure_quanta q_res *
  page47_i33
#CELL
  pure_quanta q_res *
  page47_i35
#CELL
  pure_quanta q_res *
  page47_i37
#ISCELL
  logical_power universal_gnd *
  page47_i39
#ISCELL
  standard offpage *
  page47_i40
#ISCELL
  standard offpage *
  page47_i41
#ISCELL
  standard offpage *
  page47_i42
#ISCELL
  standard offpage *
  page47_i43
#ISCELL
  standard offpage *
  page47_i44
#ISCELL
  standard offpage *
  page47_i45
#ISCELL
  standard offpage *
  page47_i46
#ISCELL
  standard offpage *
  page47_i47
#CELL
  pure_quanta q_res *
  page47_i48
#ISCELL
  standard offpage *
  page47_i49
#CELL
  pure_quanta q_led *
  page47_i5
#CELL
  pure_quanta q_res *
  page47_i50
#ISCELL
  standard offpage *
  page47_i51
#CELL
  pure_quanta q_res *
  page47_i52
#ISCELL
  standard offpage *
  page47_i53
#CELL
  pure_quanta q_res *
  page47_i54
#ISCELL
  standard offpage *
  page47_i55
#CELL
  pure_quanta q_res *
  page47_i56
#ISCELL
  standard offpage *
  page47_i57
#CELL
  pure_quanta q_res *
  page47_i58
#ISCELL
  standard offpage *
  page47_i59
#CELL
  pure_quanta q_res *
  page47_i60
#ISCELL
  standard offpage *
  page47_i61
#CELL
  pure_quanta q_res *
  page47_i62
#ISCELL
  standard offpage *
  page47_i63
#CELL
  pure_quanta q_led *
  page47_i7
#CELL
  pure_quanta q_led *
  page47_i9
#ISCELL
  mstr_misc dns *
  *
#ISCELL
  pure_quanta quanta_title_block_c *
  *
#ISCELL
  logical_power universal_gnd *
  page48_i24
#ISCELL
  logical_power vccaux15 *
  page48_i25
#ISCELL
  standard offpage *
  page48_i31
#CELL
  pure_quanta q_res *
  page48_i33
#ISCELL
  standard offpage *
  page48_i37
#ISCELL
  logical_power universal_gnd *
  page48_i38
#CELL
  pure_quanta q_res *
  page48_i39
#CELL
  pure_quanta q_res *
  page48_i40
#ISCELL
  logical_power vccaux15 *
  page48_i41
#CELL
  pure_quanta q_res *
  page48_i42
#ISCELL
  standard offpage *
  page48_i45
#ISCELL
  standard offpage *
  page48_i46
#ISCELL
  logical_power vccaux15 *
  page48_i47
#CELL
  pure_quanta q_res *
  page48_i48
#ISCELL
  logical_power vccaux15 *
  page48_i49
#CELL
  pure_quanta q_res *
  page48_i50
#CELL
  pure_quanta q_res *
  page48_i51
#CELL
  pure_quanta q_res *
  page48_i52
#CELL
  pure_quanta q_res *
  page48_i53
#ISCELL
  logical_power universal_gnd *
  page48_i54
#ISCELL
  logical_power universal_gnd *
  page48_i55
#CELL
  pure_quanta q_res *
  page48_i56
#ISCELL
  logical_power design_note *
  *
#ISCELL
  mstr_misc dns *
  *
#ISCELL
  pure_quanta quanta_title_block_c *
  *
#ISCELL
  logical_power universal_gnd *
  page49_i1
#ISCELL
  standard offpage *
  page49_i10
#CELL
  pure_quanta 74lvc1g126se7 *
  page49_i11
#ISCELL
  logical_power universal_gnd *
  page49_i12
#CELL
  pure_quanta q_cap *
  page49_i13
#ISCELL
  logical_power vccaux15 *
  page49_i14
#ISCELL
  logical_power universal_gnd *
  page49_i16
#ISCELL
  logical_power vccaux15 *
  page49_i17
#ISCELL
  standard offpage *
  page49_i19
#ISCELL
  standard offpage *
  page49_i20
#ISCELL
  logical_power universal_gnd *
  page49_i21
#CELL
  pure_quanta q_res *
  page49_i22
#ISCELL
  logical_power universal_gnd *
  page49_i23
#CELL
  pure_quanta mosfet_dual_6p *
  page49_i24
#ISCELL
  logical_power universal_gnd *
  page49_i25
#CELL
  pure_quanta q_res *
  page49_i26
#ISCELL
  logical_power universal_gnd *
  page49_i27
#ISCELL
  standard offpage *
  page49_i28
#ISCELL
  standard offpage *
  page49_i29
#ISCELL
  logical_power universal_gnd *
  page49_i3
#ISCELL
  logical_power vccaux15 *
  page49_i31
#ISCELL
  standard offpage *
  page49_i32
#ISCELL
  standard offpage *
  page49_i33
#CELL
  pure_quanta q_res *
  page49_i34
#CELL
  pure_quanta q_res *
  page49_i35
#CELL
  pure_quanta q_res *
  page49_i36
#CELL
  pure_quanta q_cap *
  page49_i37
#CELL
  pure_quanta q_cap *
  page49_i38
#ISCELL
  logical_power universal_gnd *
  page49_i4
#CELL
  pure_quanta q_res *
  page49_i40
#CELL
  pure_quanta q_cap *
  page49_i43
#CELL
  pure_quanta q_cap *
  page49_i45
#ISCELL
  logical_power universal_gnd *
  page49_i46
#ISCELL
  logical_power universal_power *
  page49_i48
#ISCELL
  logical_power universal_gnd *
  page49_i49
#CELL
  pure_quanta mc74vhc1g32dtt1g *
  page49_i5
#CELL
  pure_quanta q_led *
  page49_i50
#CELL
  pure_quanta q_led *
  page49_i51
#ISCELL
  logical_power vccaux15 *
  page49_i52
#ISCELL
  standard offpage *
  page49_i55
#ISCELL
  standard offpage *
  page49_i56
#ISCELL
  logical_power universal_power *
  page49_i58
#CELL
  pure_quanta q_res *
  page49_i59
#CELL
  pure_quanta mosfet_nch_dual *
  page49_i6
#CELL
  pure_quanta q_res *
  page49_i60
#ISCELL
  logical_power universal_gnd *
  page49_i7
#CELL
  pure_quanta q_cap *
  page49_i75
#CELL
  pure_quanta q_res *
  page49_i79
#CELL
  pure_quanta q_res *
  page49_i8
#CELL
  pure_quanta q_res *
  page49_i88
#CELL
  pure_quanta q_res *
  page49_i89
#ISCELL
  standard offpage *
  page49_i9
#CELL
  pure_quanta q_res *
  page49_i92
#ISCELL
  standard offpage *
  page49_i93
#CELL
  pure_quanta q_led *
  page49_i94
#CELL
  pure_quanta q_led *
  page49_i95
#CELL
  pure_quanta q_led *
  page49_i97
#ISCELL
  logical_power bom_note *
  *
#ISCELL
  mstr_misc dns *
  *
#ISCELL
  pure_quanta quanta_title_block_c *
  *
#ISCELL
  logical_power universal_gnd *
  page50_i138
#CELL
  pure_quanta 74lvc1g07gw *
  page50_i151
#CELL
  pure_quanta q_res *
  page50_i152
#ISCELL
  standard offpage *
  page50_i153
#CELL
  pure_quanta q_res *
  page50_i154
#ISCELL
  standard offpage *
  page50_i155
#CELL
  pure_quanta bas70057f *
  page50_i161
#ISCELL
  standard offpage *
  page50_i162
#ISCELL
  logical_power vccaux15 *
  page50_i163
#ISCELL
  logical_power universal_power *
  page50_i164
#CELL
  pure_quanta q_cap *
  page50_i165
#ISCELL
  logical_power universal_gnd *
  page50_i166
#ISCELL
  logical_power universal_gnd *
  page50_i169
#ISCELL
  logical_power universal_gnd *
  page50_i192
#CELL
  pure_quanta sw_pushbutton4p_12_g34_h2 *
  page50_i204
#ISCELL
  logical_power universal_gnd *
  page50_i208
#CELL
  pure_quanta q_res *
  page50_i210
#ISCELL
  logical_power universal_power *
  page50_i211
#CELL
  pure_quanta q_cap *
  page50_i212
#ISCELL
  logical_power universal_gnd *
  page50_i217
#CELL
  pure_quanta mosfet_nch_dual *
  page50_i218
#ISCELL
  standard offpage *
  page50_i219
#ISCELL
  logical_power universal_power *
  page50_i220
#CELL
  pure_quanta q_res *
  page50_i222
#CELL
  pure_quanta q_res *
  page50_i224
#CELL
  pure_quanta q_res *
  page50_i225
#ISCELL
  logical_power universal_gnd *
  page50_i226
#CELL
  pure_quanta 74lvc1g07gw *
  page50_i227
#ISCELL
  standard offpage *
  page50_i230
#ISCELL
  logical_power vccaux15 *
  page50_i231
#CELL
  pure_quanta q_cap *
  page50_i232
#ISCELL
  logical_power universal_gnd *
  page50_i233
#ISCELL
  logical_power vccaux15 *
  page50_i234
#CELL
  pure_quanta q_res *
  page50_i235
#CELL
  pure_quanta q_cap *
  page50_i236
#ISCELL
  logical_power universal_gnd *
  page50_i238
#ISCELL
  logical_power universal_gnd *
  page50_i239
#CELL
  pure_quanta q_res *
  page50_i241
#CELL
  pure_quanta q_res *
  page50_i242
#ISCELL
  standard offpage *
  page50_i243
#CELL
  pure_quanta diode_bidirectional *
  page50_i244
#ISCELL
  logical_power universal_gnd *
  page50_i245
#CELL
  pure_quanta q_cap *
  page50_i246
#ISCELL
  logical_power universal_gnd *
  page50_i247
#CELL
  pure_quanta 74lvc1g07gw *
  page50_i278
#ISCELL
  standard offpage *
  page50_i279
#ISCELL
  logical_power vccaux15 *
  page50_i280
#CELL
  pure_quanta q_cap *
  page50_i281
#ISCELL
  logical_power universal_gnd *
  page50_i282
#ISCELL
  logical_power vccaux15 *
  page50_i283
#CELL
  pure_quanta q_res *
  page50_i284
#CELL
  pure_quanta q_cap *
  page50_i285
#CELL
  pure_quanta q_res *
  page50_i286
#ISCELL
  logical_power universal_gnd *
  page50_i287
#CELL
  pure_quanta sw_pushbutton4p_12_g34_h2 *
  page50_i292
#CELL
  pure_quanta sw_pushbutton4p_12_g34_h2 *
  page50_i293
#CELL
  pure_quanta q_led *
  page50_i294
#CELL
  pure_quanta q_led *
  page50_i295
#ISCELL
  logical_power universal_gnd *
  page50_i30
#ISCELL
  standard offpage *
  page50_i31
#CELL
  pure_quanta q_cap *
  page50_i43
#CELL
  pure_quanta q_cap *
  page50_i44
#ISCELL
  logical_power vccaux15 *
  page50_i45
#ISCELL
  logical_power universal_gnd *
  page50_i46
#ISCELL
  standard offpage *
  page50_i48
#CELL
  pure_quanta 74lvc1g17gw *
  page50_i49
#ISCELL
  logical_power vccaux15 *
  page50_i50
#CELL
  pure_quanta q_cap *
  page50_i51
#ISCELL
  logical_power universal_gnd *
  page50_i52
#CELL
  pure_quanta q_cap *
  page50_i55
#CELL
  pure_quanta q_res *
  page50_i82
#ISCELL
  logical_power vccaux15 *
  page50_i83
#CELL
  pure_quanta q_res *
  page50_i89
#ISCELL
  logical_power vccaux15 *
  page50_i90
#ISCELL
  logical_power cad_note *
  *
#ISCELL
  logical_power design_note *
  *
#ISCELL
  mstr_misc dns *
  *
#ISCELL
  pure_quanta quanta_title_block_c *
  *
#CELL
  pure_quanta q_cap *
  page51_i1
#ISCELL
  logical_power universal_gnd *
  page51_i10
#ISCELL
  logical_power universal_gnd *
  page51_i12
#CELL
  pure_quanta q_cap *
  page51_i13
#ISCELL
  logical_power universal_gnd *
  page51_i14
#ISCELL
  logical_power universal_gnd *
  page51_i19
#ISCELL
  logical_power universal_gnd *
  page51_i2
#ISCELL
  logical_power universal_gnd *
  page51_i20
#CELL
  pure_quanta q_res *
  page51_i21
#CELL
  pure_quanta q_cap *
  page51_i22
#CELL
  pure_quanta q_cap *
  page51_i23
#ISCELL
  logical_power vccaux15 *
  page51_i24
#ISCELL
  logical_power universal_gnd *
  page51_i25
#CELL
  pure_quanta q_res *
  page51_i26
#CELL
  pure_quanta q_cap *
  page51_i27
#CELL
  pure_quanta q_inductor *
  page51_i28
#CELL
  pure_quanta q_res *
  page51_i3
#CELL
  pure_quanta q_res *
  page51_i30
#CELL
  pure_quanta q_cap *
  page51_i31
#CELL
  pure_quanta q_cap *
  page51_i32
#CELL
  pure_quanta q_cap *
  page51_i33
#ISCELL
  logical_power universal_gnd *
  page51_i35
#CELL
  pure_quanta q_cap *
  page51_i36
#CELL
  pure_quanta q_cap *
  page51_i37
#ISCELL
  logical_power vccaux15 *
  page51_i38
#CELL
  pure_quanta q_inductor *
  page51_i39
#CELL
  pure_quanta q_res *
  page51_i4
#CELL
  pure_quanta mpq8633aglec807z *
  page51_i42
#CELL
  pure_quanta q_res *
  page51_i43
#ISCELL
  logical_power universal_gnd *
  page51_i44
#CELL
  pure_quanta q_cap *
  page51_i45
#ISCELL
  standard offpage *
  page51_i46
#CELL
  pure_quanta q_cap *
  page51_i47
#CELL
  pure_quanta q_cap *
  page51_i48
#CELL
  pure_quanta q_cap *
  page51_i49
#ISCELL
  logical_power vccaux15 *
  page51_i5
#ISCELL
  logical_power universal_gnd *
  page51_i50
#CELL
  pure_quanta q_res *
  page51_i51
#CELL
  pure_quanta q_cap *
  page51_i52
#ISCELL
  logical_power universal_gnd *
  page51_i53
#CELL
  pure_quanta q_res *
  page51_i54
#ISCELL
  standard offpage *
  page51_i55
#CELL
  pure_quanta ap2205w57 *
  page51_i56
#CELL
  pure_quanta q_res *
  page51_i57
#ISCELL
  logical_power universal_gnd *
  page51_i58
#ISCELL
  logical_power universal_power *
  page51_i59
#ISCELL
  logical_power vccaux15 *
  page51_i6
#CELL
  pure_quanta q_cap *
  page51_i60
#ISCELL
  logical_power universal_gnd *
  page51_i61
#CELL
  pure_quanta q_res *
  page51_i62
#ISCELL
  logical_power universal_gnd *
  page51_i63
#ISCELL
  logical_power universal_gnd *
  page51_i65
#ISCELL
  logical_power universal_power *
  page51_i66
#CELL
  pure_quanta q_cap *
  page51_i68
#ISCELL
  logical_power universal_gnd *
  page51_i8
#CELL
  pure_quanta q_res *
  page51_i9
#ISCELL
  logical_power cad_note *
  *
#ISCELL
  mstr_misc dns *
  *
#ISCELL
  pure_quanta quanta_title_block_c *
  *
#ISCELL
  standard offpage *
  page52_i1
#ISCELL
  logical_power universal_gnd *
  page52_i100
#CELL
  pure_quanta q_cap *
  page52_i101
#CELL
  pure_quanta q_cap *
  page52_i102
#CELL
  pure_quanta mc74vhc1g32dtt1g *
  page52_i104
#ISCELL
  standard offpage *
  page52_i105
#CELL
  pure_quanta q_cap *
  page52_i107
#ISCELL
  logical_power universal_gnd *
  page52_i109
#CELL
  pure_quanta q_cap *
  page52_i11
#ISCELL
  logical_power universal_gnd *
  page52_i112
#ISCELL
  standard offpage *
  page52_i113
#CELL
  pure_quanta 74lvc1g08gw *
  page52_i114
#ISCELL
  standard offpage *
  page52_i115
#ISCELL
  logical_power universal_gnd *
  page52_i118
#CELL
  pure_quanta q_cap *
  page52_i119
#ISCELL
  logical_power universal_gnd *
  page52_i12
#ISCELL
  logical_power universal_gnd *
  page52_i120
#ISCELL
  standard offpage *
  page52_i122
#ISCELL
  logical_power universal_gnd *
  page52_i124
#CELL
  pure_quanta q_cap *
  page52_i125
#CELL
  pure_quanta q_res *
  page52_i127
#CELL
  pure_quanta q_res *
  page52_i13
#ISCELL
  standard offpage *
  page52_i130
#ISCELL
  standard offpage *
  page52_i136
#CELL
  pure_quanta q_res *
  page52_i137
#ISCELL
  standard offpage *
  page52_i138
#CELL
  pure_quanta q_res *
  page52_i139
#ISCELL
  standard offpage *
  page52_i140
#CELL
  pure_quanta q_res *
  page52_i141
#ISCELL
  standard offpage *
  page52_i142
#ISCELL
  logical_power universal_power *
  page52_i143
#ISCELL
  logical_power universal_power *
  page52_i144
#CELL
  pure_quanta q_res *
  page52_i145
#CELL
  pure_quanta q_res *
  page52_i146
#CELL
  pure_quanta q_res *
  page52_i147
#CELL
  pure_quanta q_cap *
  page52_i15
#CELL
  pure_quanta q_res *
  page52_i17
#ISCELL
  logical_power universal_gnd *
  page52_i18
#ISCELL
  logical_power vccaux15 *
  page52_i2
#CELL
  pure_quanta q_cap *
  page52_i23
#CELL
  pure_quanta q_res *
  page52_i25
#ISCELL
  logical_power universal_gnd *
  page52_i28
#ISCELL
  logical_power vccaux15 *
  page52_i31
#CELL
  pure_quanta q_inductor *
  page52_i32
#CELL
  pure_quanta q_cap *
  page52_i35
#CELL
  pure_quanta q_cap *
  page52_i36
#CELL
  pure_quanta q_cap *
  page52_i37
#CELL
  pure_quanta q_cap *
  page52_i38
#ISCELL
  logical_power universal_power *
  page52_i39
#ISCELL
  logical_power universal_gnd *
  page52_i4
#ISCELL
  logical_power universal_gnd *
  page52_i5
#ISCELL
  standard offpage *
  page52_i55
#ISCELL
  logical_power universal_gnd *
  page52_i62
#CELL
  pure_quanta q_cap *
  page52_i63
#ISCELL
  logical_power universal_gnd *
  page52_i64
#ISCELL
  logical_power vccaux15 *
  page52_i65
#CELL
  pure_quanta q_cap *
  page52_i66
#ISCELL
  logical_power universal_gnd *
  page52_i67
#ISCELL
  logical_power universal_power *
  page52_i68
#CELL
  pure_quanta q_cap *
  page52_i73
#ISCELL
  logical_power universal_gnd *
  page52_i74
#ISCELL
  standard offpage *
  page52_i75
#CELL
  pure_quanta ap22811aw57 *
  page52_i79
#CELL
  pure_quanta q_cap *
  page52_i80
#CELL
  pure_quanta q_cap *
  page52_i81
#CELL
  pure_quanta mpq8626gdz *
  page52_i82
#ISCELL
  logical_power universal_gnd *
  page52_i84
#ISCELL
  logical_power universal_gnd *
  page52_i85
#CELL
  pure_quanta q_cap *
  page52_i86
#CELL
  pure_quanta q_res *
  page52_i87
#CELL
  pure_quanta q_res *
  page52_i88
#ISCELL
  logical_power universal_gnd *
  page52_i89
#CELL
  pure_quanta q_cap *
  page52_i9
#CELL
  pure_quanta q_cap *
  page52_i91
#CELL
  pure_quanta q_inductor *
  page52_i92
#CELL
  pure_quanta q_cap *
  page52_i93
#ISCELL
  logical_power universal_gnd *
  page52_i94
#CELL
  pure_quanta q_res *
  page52_i95
#CELL
  pure_quanta q_res *
  page52_i96
#CELL
  pure_quanta q_res *
  page52_i97
#ISCELL
  standard offpage *
  page52_i99
#ISCELL
  logical_power cad_note *
  *
#ISCELL
  mstr_misc dns *
  *
#ISCELL
  pure_quanta quanta_title_block_c *
  *
#ISCELL
  logical_power universal_gnd *
  page53_i10
#ISCELL
  logical_power universal_gnd *
  page53_i16
#ISCELL
  logical_power vccaux15 *
  page53_i2
#ISCELL
  logical_power universal_gnd *
  page53_i26
#ISCELL
  logical_power vccaux15 *
  page53_i29
#ISCELL
  logical_power vccaux15 *
  page53_i45
#ISCELL
  logical_power vccaux15 *
  page53_i48
#ISCELL
  logical_power universal_gnd *
  page53_i50
#ISCELL
  standard offpage *
  page53_i54
#CELL
  pure_quanta q_res *
  page53_i58
#CELL
  pure_quanta rt9059gqw *
  page53_i60
#CELL
  pure_quanta q_res *
  page53_i61
#CELL
  pure_quanta q_res *
  page53_i62
#ISCELL
  logical_power universal_gnd *
  page53_i63
#CELL
  pure_quanta q_cap *
  page53_i64
#CELL
  pure_quanta q_res *
  page53_i65
#ISCELL
  standard offpage *
  page53_i66
#CELL
  pure_quanta q_cap *
  page53_i67
#CELL
  pure_quanta q_res *
  page53_i68
#CELL
  pure_quanta q_cap *
  page53_i69
#CELL
  pure_quanta q_cap *
  page53_i70
#CELL
  pure_quanta q_cap *
  page53_i71
#CELL
  pure_quanta q_res *
  page53_i72
#ISCELL
  standard offpage *
  page53_i73
#ISCELL
  logical_power cad_note *
  *
#ISCELL
  mstr_misc dns *
  *
#ISCELL
  pure_quanta quanta_title_block_c *
  *
#CELL
  pure_quanta q_cap *
  page54_i100
#ISCELL
  logical_power universal_gnd *
  page54_i101
#CELL
  pure_quanta q_res *
  page54_i102
#ISCELL
  standard offpage *
  page54_i103
#CELL
  pure_quanta q_cap *
  page54_i104
#CELL
  pure_quanta q_cap *
  page54_i105
#CELL
  pure_quanta q_cap *
  page54_i106
#CELL
  pure_quanta q_cap *
  page54_i107
#CELL
  pure_quanta q_res *
  page54_i108
#ISCELL
  standard offpage *
  page54_i110
#ISCELL
  logical_power universal_gnd *
  page54_i111
#CELL
  pure_quanta q_cap *
  page54_i112
#ISCELL
  logical_power universal_gnd *
  page54_i114
#CELL
  pure_quanta mc74vhc1g32dtt1g *
  page54_i116
#ISCELL
  standard offpage *
  page54_i117
#CELL
  pure_quanta q_cap *
  page54_i130
#ISCELL
  logical_power universal_gnd *
  page54_i131
#CELL
  pure_quanta q_res *
  page54_i132
#ISCELL
  standard offpage *
  page54_i136
#CELL
  pure_quanta q_res *
  page54_i137
#ISCELL
  standard offpage *
  page54_i138
#CELL
  pure_quanta q_res *
  page54_i139
#ISCELL
  standard offpage *
  page54_i140
#ISCELL
  logical_power universal_power *
  page54_i141
#ISCELL
  logical_power universal_gnd *
  page54_i54
#ISCELL
  logical_power universal_gnd *
  page54_i58
#ISCELL
  logical_power vccaux15 *
  page54_i60
#ISCELL
  logical_power universal_gnd *
  page54_i61
#ISCELL
  logical_power universal_gnd *
  page54_i62
#ISCELL
  logical_power vccaux15 *
  page54_i64
#ISCELL
  logical_power vccaux15 *
  page54_i67
#ISCELL
  logical_power vccaux15 *
  page54_i89
#ISCELL
  standard offpage *
  page54_i90
#CELL
  pure_quanta rt9059gqw *
  page54_i96
#CELL
  pure_quanta q_res *
  page54_i97
#CELL
  pure_quanta q_res *
  page54_i98
#CELL
  pure_quanta q_res *
  page54_i99
#ISCELL
  logical_power cad_note *
  *
#ISCELL
  mstr_misc dns *
  *
#ISCELL
  pure_quanta quanta_title_block_c *
  *
#ISCELL
  logical_power universal_gnd *
  page55_i10
#ISCELL
  logical_power universal_gnd *
  page55_i14
#CELL
  pure_quanta nb695gdz *
  page55_i15
#CELL
  pure_quanta q_cap *
  page55_i16
#ISCELL
  logical_power universal_gnd *
  page55_i17
#CELL
  pure_quanta q_res *
  page55_i18
#CELL
  pure_quanta q_cap *
  page55_i19
#ISCELL
  logical_power vccaux15 *
  page55_i2
#CELL
  pure_quanta q_inductor *
  page55_i21
#CELL
  pure_quanta q_cap *
  page55_i23
#CELL
  pure_quanta q_cap *
  page55_i24
#CELL
  pure_quanta q_cap *
  page55_i25
#ISCELL
  logical_power universal_gnd *
  page55_i27
#CELL
  pure_quanta q_cap *
  page55_i28
#CELL
  pure_quanta q_cap *
  page55_i29
#ISCELL
  logical_power vccaux15 *
  page55_i30
#CELL
  pure_quanta q_inductor *
  page55_i31
#ISCELL
  logical_power vccaux15 *
  page55_i34
#ISCELL
  standard offpage *
  page55_i35
#CELL
  pure_quanta q_res *
  page55_i38
#ISCELL
  standard offpage *
  page55_i39
#ISCELL
  logical_power universal_gnd *
  page55_i4
#ISCELL
  standard offpage *
  page55_i40
#CELL
  pure_quanta q_res *
  page55_i41
#CELL
  pure_quanta q_cap *
  page55_i42
#CELL
  pure_quanta q_cap *
  page55_i43
#ISCELL
  logical_power vccaux15 *
  page55_i44
#CELL
  pure_quanta q_res *
  page55_i45
#ISCELL
  logical_power vccaux15 *
  page55_i46
#ISCELL
  logical_power vccaux15 *
  page55_i47
#CELL
  pure_quanta q_res *
  page55_i48
#ISCELL
  logical_power vccaux15 *
  page55_i49
#ISCELL
  logical_power universal_gnd *
  page55_i5
#CELL
  pure_quanta q_res *
  page55_i50
#ISCELL
  logical_power universal_gnd *
  page55_i51
#CELL
  pure_quanta q_cap *
  page55_i52
#ISCELL
  logical_power universal_gnd *
  page55_i53
#CELL
  pure_quanta q_cap *
  page55_i54
#ISCELL
  standard offpage *
  page55_i55
#ISCELL
  standard offpage *
  page55_i56
#ISCELL
  logical_power universal_gnd *
  page55_i57
#CELL
  pure_quanta q_res *
  page55_i6
#ISCELL
  logical_power universal_gnd *
  page55_i60
#CELL
  pure_quanta q_cap *
  page55_i61
#CELL
  pure_quanta 74lvc1g08gw *
  page55_i63
#ISCELL
  standard offpage *
  page55_i67
#CELL
  pure_quanta q_res *
  page55_i68
#ISCELL
  standard offpage *
  page55_i69
#CELL
  pure_quanta q_cap *
  page55_i7
#CELL
  pure_quanta q_res *
  page55_i70
#ISCELL
  standard offpage *
  page55_i71
#ISCELL
  logical_power universal_power *
  page55_i72
#CELL
  pure_quanta q_res *
  page55_i8
#ISCELL
  logical_power vccaux15 *
  page55_i9
#ISCELL
  logical_power cad_note *
  *
#ISCELL
  mstr_misc dns *
  *
#ISCELL
  pure_quanta quanta_title_block_c *
  *
#ISCELL
  logical_power universal_gnd *
  page56_i10
#ISCELL
  logical_power universal_gnd *
  page56_i14
#CELL
  pure_quanta nb695gdz *
  page56_i15
#CELL
  pure_quanta q_cap *
  page56_i16
#ISCELL
  logical_power universal_gnd *
  page56_i17
#CELL
  pure_quanta q_res *
  page56_i18
#CELL
  pure_quanta q_cap *
  page56_i19
#ISCELL
  logical_power vccaux15 *
  page56_i2
#CELL
  pure_quanta q_cap *
  page56_i23
#CELL
  pure_quanta q_cap *
  page56_i24
#CELL
  pure_quanta q_cap *
  page56_i25
#ISCELL
  logical_power universal_gnd *
  page56_i27
#CELL
  pure_quanta q_cap *
  page56_i28
#CELL
  pure_quanta q_cap *
  page56_i29
#ISCELL
  logical_power vccaux15 *
  page56_i30
#CELL
  pure_quanta q_inductor *
  page56_i34
#CELL
  pure_quanta q_inductor *
  page56_i37
#ISCELL
  logical_power vccaux15 *
  page56_i38
#ISCELL
  logical_power universal_gnd *
  page56_i4
#CELL
  pure_quanta q_cap *
  page56_i43
#CELL
  pure_quanta q_cap *
  page56_i44
#ISCELL
  logical_power vccaux15 *
  page56_i45
#ISCELL
  logical_power vccaux15 *
  page56_i46
#CELL
  pure_quanta q_res *
  page56_i47
#CELL
  pure_quanta q_res *
  page56_i48
#ISCELL
  logical_power vccaux15 *
  page56_i49
#ISCELL
  logical_power universal_gnd *
  page56_i5
#ISCELL
  logical_power vccaux15 *
  page56_i50
#CELL
  pure_quanta q_cap *
  page56_i51
#ISCELL
  logical_power universal_gnd *
  page56_i52
#ISCELL
  standard offpage *
  page56_i53
#CELL
  pure_quanta q_res *
  page56_i54
#CELL
  pure_quanta q_res *
  page56_i55
#ISCELL
  standard offpage *
  page56_i56
#ISCELL
  logical_power universal_gnd *
  page56_i57
#CELL
  pure_quanta q_cap *
  page56_i58
#ISCELL
  standard offpage *
  page56_i59
#ISCELL
  standard offpage *
  page56_i60
#ISCELL
  logical_power universal_gnd *
  page56_i61
#ISCELL
  logical_power universal_gnd *
  page56_i63
#CELL
  pure_quanta q_cap *
  page56_i64
#CELL
  pure_quanta 74lvc1g08gw *
  page56_i66
#CELL
  pure_quanta q_cap *
  page56_i7
#ISCELL
  standard offpage *
  page56_i70
#CELL
  pure_quanta q_res *
  page56_i71
#CELL
  pure_quanta q_res *
  page56_i72
#ISCELL
  standard offpage *
  page56_i73
#ISCELL
  logical_power universal_power *
  page56_i74
#CELL
  pure_quanta q_res *
  page56_i8
#ISCELL
  logical_power vccaux15 *
  page56_i9
#ISCELL
  logical_power bom_note *
  *
#ISCELL
  mstr_misc dns *
  *
#ISCELL
  pure_quanta quanta_title_block_c *
  *
#ISCELL
  standard gnd_power *
  page57_i1
#CELL
  pure_quanta hole *
  page57_i14
#ISCELL
  standard gnd_power *
  page57_i31
#ISCELL
  standard gnd_power *
  page57_i33
#CELL
  pure_quanta hole *
  page57_i34
#CELL
  pure_quanta hole *
  page57_i35
#CELL
  pure_quanta hole *
  page57_i36
#ISCELL
  standard gnd_power *
  page57_i37
#CELL
  pure_quanta hole *
  page57_i38
#ISCELL
  standard gnd_power *
  page57_i39
#CELL
  pure_quanta hole *
  page57_i40
#ISCELL
  standard gnd_power *
  page57_i41
#ISCELL
  standard gnd_power *
  page57_i43
#CELL
  pure_quanta hole *
  page57_i45
#CELL
  pure_quanta hole *
  page57_i49
#CELL
  pure_quanta hole *
  page57_i50
#CELL
  pure_quanta hole *
  page57_i51
#ISCELL
  pure_quanta quanta_title_block_c *
  *
#ISCELL
  logical_power universal_gnd *
  page58_i18
#ISCELL
  logical_power universal_gnd *
  page58_i2
#ISCELL
  logical_power universal_gnd *
  page58_i25
#ISCELL
  logical_power universal_gnd *
  page58_i35
#ISCELL
  logical_power universal_gnd *
  page58_i39
#ISCELL
  logical_power universal_gnd *
  page58_i40
#ISCELL
  logical_power universal_gnd *
  page58_i46
#ISCELL
  logical_power universal_gnd *
  page58_i47
#ISCELL
  logical_power universal_gnd *
  page58_i48
#ISCELL
  logical_power universal_gnd *
  page58_i49
#ISCELL
  logical_power universal_gnd *
  page58_i5
#ISCELL
  logical_power universal_gnd *
  page58_i50
#ISCELL
  logical_power universal_gnd *
  page58_i51
#ISCELL
  logical_power universal_gnd *
  page58_i52
#ISCELL
  logical_power universal_gnd *
  page58_i53
#ISCELL
  logical_power universal_gnd *
  page58_i54
#CELL
  pure_quanta picoprobe_bxa *
  page58_i55
#CELL
  pure_quanta picoprobe_bxa *
  page58_i57
#CELL
  pure_quanta picoprobe_bxa *
  page58_i58
#CELL
  pure_quanta picoprobe_bxa *
  page58_i59
#CELL
  pure_quanta picoprobe_bxa *
  page58_i60
#CELL
  pure_quanta picoprobe_bxa *
  page58_i61
#CELL
  pure_quanta picoprobe_bxa *
  page58_i62
#CELL
  pure_quanta picoprobe_bxa *
  page58_i63
#CELL
  pure_quanta picoprobe_bxa *
  page58_i64
#CELL
  pure_quanta picoprobe_bxa *
  page58_i65
#CELL
  pure_quanta picoprobe_bxa *
  page58_i66
#CELL
  pure_quanta picoprobe_bxa *
  page58_i67
#CELL
  pure_quanta picoprobe_bxa *
  page58_i68
#CELL
  pure_quanta picoprobe_bxa *
  page58_i69
#CELL
  pure_quanta picoprobe_bxa *
  page58_i70
#CELL
  pure_quanta picoprobe_bxa *
  page58_i71
#ISCELL
  mstr_misc dns *
  *
#ISCELL
  pure_quanta quanta_title_block_c *
  *
#CELL
  pure_quanta me_dummy_symbol *
  page59_i27
#CELL
  pure_quanta me_dummy_symbol *
  page59_i28
#CELL
  pure_quanta me_dummy_symbol *
  page59_i29
#CELL
  pure_quanta me_dummy_symbol *
  page59_i34
#CELL
  pure_quanta dummy_symbol *
  page59_i35
#CELL
  pure_quanta dummy_symbol *
  page59_i36
#CELL
  pure_quanta dummy_symbol *
  page59_i37
#ISCELL
  pure_quanta quanta_title_block_c *
  *
#CELL
  pure_quanta tdr_3p *
  page60_i1
#ISCELL
  logical_power universal_gnd *
  page60_i10
#CELL
  pure_quanta tdr_3p *
  page60_i11
#ISCELL
  logical_power universal_gnd *
  page60_i12
#CELL
  pure_quanta tp_tdr_4p_fts *
  page60_i13
#CELL
  pure_quanta tp_tdr_4p_fts *
  page60_i14
#CELL
  pure_quanta tp_tdr_4p_fts *
  page60_i18
#CELL
  pure_quanta tp_tdr_4p_fts *
  page60_i19
#ISCELL
  logical_power universal_gnd *
  page60_i2
#CELL
  pure_quanta tp_tdr_4p_fts *
  page60_i22
#CELL
  pure_quanta tp_tdr_4p_fts *
  page60_i23
#CELL
  pure_quanta tdr_3p *
  page60_i3
#CELL
  pure_quanta tp_tdr_4p_fts *
  page60_i34
#CELL
  pure_quanta tp_tdr_4p_fts *
  page60_i35
#CELL
  pure_quanta tp_tdr_4p_fts *
  page60_i38
#CELL
  pure_quanta tp_tdr_4p_fts *
  page60_i39
#ISCELL
  logical_power universal_gnd *
  page60_i4
#CELL
  pure_quanta tp_tdr_4p_fts *
  page60_i42
#CELL
  pure_quanta tp_tdr_4p_fts *
  page60_i43
#CELL
  pure_quanta tp_tdr_4p_fts *
  page60_i46
#CELL
  pure_quanta tp_tdr_4p_fts *
  page60_i47
#CELL
  pure_quanta tdr_3p *
  page60_i5
#CELL
  pure_quanta tp_tdr_4p_fts *
  page60_i58
#CELL
  pure_quanta tp_tdr_4p_fts *
  page60_i59
#ISCELL
  logical_power universal_gnd *
  page60_i6
#ISCELL
  logical_power universal_gnd *
  page60_i61
#ISCELL
  logical_power universal_gnd *
  page60_i62
#ISCELL
  logical_power universal_gnd *
  page60_i63
#ISCELL
  logical_power universal_gnd *
  page60_i64
#ISCELL
  logical_power universal_gnd *
  page60_i65
#ISCELL
  logical_power universal_gnd *
  page60_i66
#ISCELL
  logical_power universal_gnd *
  page60_i67
#ISCELL
  logical_power universal_gnd *
  page60_i68
#ISCELL
  logical_power universal_gnd *
  page60_i69
#CELL
  pure_quanta tdr_3p *
  page60_i7
#ISCELL
  logical_power universal_gnd *
  page60_i70
#ISCELL
  logical_power universal_gnd *
  page60_i71
#ISCELL
  logical_power universal_gnd *
  page60_i72
#ISCELL
  logical_power universal_gnd *
  page60_i73
#ISCELL
  logical_power universal_gnd *
  page60_i74
#ISCELL
  logical_power universal_gnd *
  page60_i75
#ISCELL
  logical_power universal_gnd *
  page60_i76
#ISCELL
  logical_power universal_gnd *
  page60_i8
#CELL
  pure_quanta tdr_3p *
  page60_i9
